FILE_TYPE = MACRO_DRAWING;
SET COLOR_WIRE YELLOW;
SET COLOR_PROP MONO;
SET COLOR_DOT WHITE;
SET COLOR_ARC YELLOW;
SET COLOR_BODY GREEN;
SET COLOR_NOTE MONO;
SET PROP_DISPLAY VALUE;
SET PAGE_NUMBER P85;
FORCEADD OFFPAGE..3
(1600 5200);
FORCEPROP 2 LAST $XR0 61 
J 0
(1814 5200);
DISPLAY 0.638298 (1814 5200);
PAINT MONO (1814 5200);
FORCEPROP 2 LAST $XR1 86 
J 0
(1904 5200);
DISPLAY 0.638298 (1904 5200);
PAINT MONO (1904 5200);
FORCEPROP 2 LAST CDS_LIB mstr_standard
J 0
(1600 5200);
DISPLAY 0.787234 (1600 5200);
PAINT MONO (1600 5200);
DISPLAY INVISIBLE (1600 5200);
FORCEPROP 1 LAST OFFPAGE TRUE
J 0
(1925 5075);
DISPLAY 0.936170 (1925 5075);
PAINT GREEN (1925 5075);
DISPLAY INVISIBLE (1925 5075);
FORCEPROP 1 LAST COMMENT_BODY TRUE
J 0
(1550 5100);
DISPLAY 0.936170 (1550 5100);
PAINT GREEN (1550 5100);
DISPLAY INVISIBLE (1550 5100);
FORCEPROP 2 LAST PATH I1
J 0
(1800 5275);
DISPLAY 0.787234 (1800 5275);
PAINT MONO (1800 5275);
DISPLAY INVISIBLE (1800 5275);
FORCEADD TAP..6
R 2
(700 4850);
FORCEPROP 3 LASTPIN (650 4850) SIG_NAME M_L_DQS_DP<14>
J 0
(660 4860);
DISPLAY 0.659574 (660 4860);
PAINT MONO (660 4860);
DISPLAY INVISIBLE (660 4860);
FORCEPROP 1 LASTPIN (650 4850) BN 14
J 2
(700 4860);
DISPLAY 0.617021 (700 4860);
PAINT PINK (700 4860);
FORCEPROP 2 LAST CDS_LIB mstr_standard
J 0
(700 4850);
DISPLAY 0.787234 (700 4850);
PAINT MONO (700 4850);
DISPLAY INVISIBLE (700 4850);
FORCEPROP 1 LAST BODY_TYPE PLUMBING
J 2
(700 4800);
DISPLAY 1.234043 (700 4800);
PAINT GREEN (700 4800);
DISPLAY INVISIBLE (700 4800);
FORCEPROP 1 LAST HDL_TAP TRUE
J 2
(375 4725);
DISPLAY 1.234043 (375 4725);
PAINT GREEN (375 4725);
DISPLAY INVISIBLE (375 4725);
FORCEPROP 1 LAST PATH I10
J 2
(700 4850);
DISPLAY 0.936170 (700 4850);
PAINT GREEN (700 4850);
DISPLAY INVISIBLE (700 4850);
FORCEADD TAP..6
R 2
(-1750 2200);
FORCEPROP 3 LASTPIN (-1800 2200) SIG_NAME M_L_DQ<8>
J 0
(-1790 2210);
DISPLAY 0.659574 (-1790 2210);
PAINT MONO (-1790 2210);
DISPLAY INVISIBLE (-1790 2210);
FORCEPROP 1 LASTPIN (-1800 2200) BN 8
J 2
(-1750 2210);
DISPLAY 0.617021 (-1750 2210);
PAINT PINK (-1750 2210);
FORCEPROP 2 LAST CDS_LIB mstr_standard
J 2
(-1750 2200);
DISPLAY 0.787234 (-1750 2200);
PAINT MONO (-1750 2200);
DISPLAY INVISIBLE (-1750 2200);
FORCEPROP 1 LAST BODY_TYPE PLUMBING
J 2
(-1750 2150);
DISPLAY 1.234043 (-1750 2150);
PAINT GREEN (-1750 2150);
DISPLAY INVISIBLE (-1750 2150);
FORCEPROP 1 LAST HDL_TAP TRUE
J 2
(-2075 2075);
DISPLAY 1.234043 (-2075 2075);
PAINT GREEN (-2075 2075);
DISPLAY INVISIBLE (-2075 2075);
FORCEPROP 1 LAST PATH I100
J 2
(-1750 2200);
DISPLAY 0.936170 (-1750 2200);
PAINT GREEN (-1750 2200);
DISPLAY INVISIBLE (-1750 2200);
FORCEADD TAP..6
R 2
(-1750 2250);
FORCEPROP 3 LASTPIN (-1800 2250) SIG_NAME M_L_DQ<11>
J 0
(-1790 2260);
DISPLAY 0.659574 (-1790 2260);
PAINT MONO (-1790 2260);
DISPLAY INVISIBLE (-1790 2260);
FORCEPROP 1 LASTPIN (-1800 2250) BN 11
J 2
(-1750 2260);
DISPLAY 0.617021 (-1750 2260);
PAINT PINK (-1750 2260);
FORCEPROP 2 LAST CDS_LIB mstr_standard
J 2
(-1750 2250);
DISPLAY 0.787234 (-1750 2250);
PAINT MONO (-1750 2250);
DISPLAY INVISIBLE (-1750 2250);
FORCEPROP 1 LAST BODY_TYPE PLUMBING
J 2
(-1750 2200);
DISPLAY 1.234043 (-1750 2200);
PAINT GREEN (-1750 2200);
DISPLAY INVISIBLE (-1750 2200);
FORCEPROP 1 LAST HDL_TAP TRUE
J 2
(-2075 2125);
DISPLAY 1.234043 (-2075 2125);
PAINT GREEN (-2075 2125);
DISPLAY INVISIBLE (-2075 2125);
FORCEPROP 1 LAST PATH I101
J 2
(-1750 2250);
DISPLAY 0.936170 (-1750 2250);
PAINT GREEN (-1750 2250);
DISPLAY INVISIBLE (-1750 2250);
FORCEADD TAP..6
R 2
(-1750 1950);
FORCEPROP 3 LASTPIN (-1800 1950) SIG_NAME M_L_DQ<5>
J 0
(-1790 1960);
DISPLAY 0.659574 (-1790 1960);
PAINT MONO (-1790 1960);
DISPLAY INVISIBLE (-1790 1960);
FORCEPROP 1 LASTPIN (-1800 1950) BN 5
J 2
(-1750 1960);
DISPLAY 0.617021 (-1750 1960);
PAINT PINK (-1750 1960);
FORCEPROP 2 LAST CDS_LIB mstr_standard
J 2
(-1750 1950);
DISPLAY 0.787234 (-1750 1950);
PAINT MONO (-1750 1950);
DISPLAY INVISIBLE (-1750 1950);
FORCEPROP 1 LAST BODY_TYPE PLUMBING
J 2
(-1750 1900);
DISPLAY 1.234043 (-1750 1900);
PAINT GREEN (-1750 1900);
DISPLAY INVISIBLE (-1750 1900);
FORCEPROP 1 LAST HDL_TAP TRUE
J 2
(-2075 1825);
DISPLAY 1.234043 (-2075 1825);
PAINT GREEN (-2075 1825);
DISPLAY INVISIBLE (-2075 1825);
FORCEPROP 1 LAST PATH I102
J 2
(-1750 1950);
DISPLAY 0.936170 (-1750 1950);
PAINT GREEN (-1750 1950);
DISPLAY INVISIBLE (-1750 1950);
FORCEADD TAP..6
R 2
(-1750 1900);
FORCEPROP 3 LASTPIN (-1800 1900) SIG_NAME M_L_DQ<2>
J 0
(-1790 1910);
DISPLAY 0.659574 (-1790 1910);
PAINT MONO (-1790 1910);
DISPLAY INVISIBLE (-1790 1910);
FORCEPROP 1 LASTPIN (-1800 1900) BN 2
J 2
(-1750 1910);
DISPLAY 0.617021 (-1750 1910);
PAINT PINK (-1750 1910);
FORCEPROP 2 LAST CDS_LIB mstr_standard
J 2
(-1750 1900);
DISPLAY 0.787234 (-1750 1900);
PAINT MONO (-1750 1900);
DISPLAY INVISIBLE (-1750 1900);
FORCEPROP 1 LAST BODY_TYPE PLUMBING
J 2
(-1750 1850);
DISPLAY 1.234043 (-1750 1850);
PAINT GREEN (-1750 1850);
DISPLAY INVISIBLE (-1750 1850);
FORCEPROP 1 LAST HDL_TAP TRUE
J 2
(-2075 1775);
DISPLAY 1.234043 (-2075 1775);
PAINT GREEN (-2075 1775);
DISPLAY INVISIBLE (-2075 1775);
FORCEPROP 1 LAST PATH I103
J 2
(-1750 1900);
DISPLAY 0.936170 (-1750 1900);
PAINT GREEN (-1750 1900);
DISPLAY INVISIBLE (-1750 1900);
FORCEADD TAP..6
R 2
(-1750 2000);
FORCEPROP 3 LASTPIN (-1800 2000) SIG_NAME M_L_DQ<4>
J 0
(-1790 2010);
DISPLAY 0.659574 (-1790 2010);
PAINT MONO (-1790 2010);
DISPLAY INVISIBLE (-1790 2010);
FORCEPROP 1 LASTPIN (-1800 2000) BN 4
J 2
(-1750 2010);
DISPLAY 0.617021 (-1750 2010);
PAINT PINK (-1750 2010);
FORCEPROP 2 LAST CDS_LIB mstr_standard
J 2
(-1750 2000);
DISPLAY 0.787234 (-1750 2000);
PAINT MONO (-1750 2000);
DISPLAY INVISIBLE (-1750 2000);
FORCEPROP 1 LAST BODY_TYPE PLUMBING
J 2
(-1750 1950);
DISPLAY 1.234043 (-1750 1950);
PAINT GREEN (-1750 1950);
DISPLAY INVISIBLE (-1750 1950);
FORCEPROP 1 LAST HDL_TAP TRUE
J 2
(-2075 1875);
DISPLAY 1.234043 (-2075 1875);
PAINT GREEN (-2075 1875);
DISPLAY INVISIBLE (-2075 1875);
FORCEPROP 1 LAST PATH I104
J 2
(-1750 2000);
DISPLAY 0.936170 (-1750 2000);
PAINT GREEN (-1750 2000);
DISPLAY INVISIBLE (-1750 2000);
FORCEADD TAP..6
R 2
(-1750 2050);
FORCEPROP 3 LASTPIN (-1800 2050) SIG_NAME M_L_DQ<7>
J 0
(-1790 2060);
DISPLAY 0.659574 (-1790 2060);
PAINT MONO (-1790 2060);
DISPLAY INVISIBLE (-1790 2060);
FORCEPROP 1 LASTPIN (-1800 2050) BN 7
J 2
(-1750 2060);
DISPLAY 0.617021 (-1750 2060);
PAINT PINK (-1750 2060);
FORCEPROP 2 LAST CDS_LIB mstr_standard
J 2
(-1750 2050);
DISPLAY 0.787234 (-1750 2050);
PAINT MONO (-1750 2050);
DISPLAY INVISIBLE (-1750 2050);
FORCEPROP 1 LAST BODY_TYPE PLUMBING
J 2
(-1750 2000);
DISPLAY 1.234043 (-1750 2000);
PAINT GREEN (-1750 2000);
DISPLAY INVISIBLE (-1750 2000);
FORCEPROP 1 LAST HDL_TAP TRUE
J 2
(-2075 1925);
DISPLAY 1.234043 (-2075 1925);
PAINT GREEN (-2075 1925);
DISPLAY INVISIBLE (-2075 1925);
FORCEPROP 1 LAST PATH I105
J 2
(-1750 2050);
DISPLAY 0.936170 (-1750 2050);
PAINT GREEN (-1750 2050);
DISPLAY INVISIBLE (-1750 2050);
FORCEADD TAP..6
R 2
(-1750 2150);
FORCEPROP 3 LASTPIN (-1800 2150) SIG_NAME M_L_DQ<9>
J 0
(-1790 2160);
DISPLAY 0.659574 (-1790 2160);
PAINT MONO (-1790 2160);
DISPLAY INVISIBLE (-1790 2160);
FORCEPROP 1 LASTPIN (-1800 2150) BN 9
J 2
(-1750 2160);
DISPLAY 0.617021 (-1750 2160);
PAINT PINK (-1750 2160);
FORCEPROP 2 LAST CDS_LIB mstr_standard
J 2
(-1750 2150);
DISPLAY 0.787234 (-1750 2150);
PAINT MONO (-1750 2150);
DISPLAY INVISIBLE (-1750 2150);
FORCEPROP 1 LAST BODY_TYPE PLUMBING
J 2
(-1750 2100);
DISPLAY 1.234043 (-1750 2100);
PAINT GREEN (-1750 2100);
DISPLAY INVISIBLE (-1750 2100);
FORCEPROP 1 LAST HDL_TAP TRUE
J 2
(-2075 2025);
DISPLAY 1.234043 (-2075 2025);
PAINT GREEN (-2075 2025);
DISPLAY INVISIBLE (-2075 2025);
FORCEPROP 1 LAST PATH I106
J 2
(-1750 2150);
DISPLAY 0.936170 (-1750 2150);
PAINT GREEN (-1750 2150);
DISPLAY INVISIBLE (-1750 2150);
FORCEADD TAP..6
R 2
(-1750 2100);
FORCEPROP 3 LASTPIN (-1800 2100) SIG_NAME M_L_DQ<6>
J 0
(-1790 2110);
DISPLAY 0.659574 (-1790 2110);
PAINT MONO (-1790 2110);
DISPLAY INVISIBLE (-1790 2110);
FORCEPROP 1 LASTPIN (-1800 2100) BN 6
J 2
(-1750 2110);
DISPLAY 0.617021 (-1750 2110);
PAINT PINK (-1750 2110);
FORCEPROP 2 LAST CDS_LIB mstr_standard
J 2
(-1750 2100);
DISPLAY 0.787234 (-1750 2100);
PAINT MONO (-1750 2100);
DISPLAY INVISIBLE (-1750 2100);
FORCEPROP 1 LAST BODY_TYPE PLUMBING
J 2
(-1750 2050);
DISPLAY 1.234043 (-1750 2050);
PAINT GREEN (-1750 2050);
DISPLAY INVISIBLE (-1750 2050);
FORCEPROP 1 LAST HDL_TAP TRUE
J 2
(-2075 1975);
DISPLAY 1.234043 (-2075 1975);
PAINT GREEN (-2075 1975);
DISPLAY INVISIBLE (-2075 1975);
FORCEPROP 1 LAST PATH I107
J 2
(-1750 2100);
DISPLAY 0.936170 (-1750 2100);
PAINT GREEN (-1750 2100);
DISPLAY INVISIBLE (-1750 2100);
FORCEADD TAP..6
R 2
(-1750 1750);
FORCEPROP 3 LASTPIN (-1800 1750) SIG_NAME M_L_DQ<1>
J 0
(-1790 1760);
DISPLAY 0.659574 (-1790 1760);
PAINT MONO (-1790 1760);
DISPLAY INVISIBLE (-1790 1760);
FORCEPROP 1 LASTPIN (-1800 1750) BN 1
J 2
(-1750 1760);
DISPLAY 0.617021 (-1750 1760);
PAINT PINK (-1750 1760);
FORCEPROP 2 LAST CDS_LIB mstr_standard
J 2
(-1750 1750);
DISPLAY 0.787234 (-1750 1750);
PAINT MONO (-1750 1750);
DISPLAY INVISIBLE (-1750 1750);
FORCEPROP 1 LAST BODY_TYPE PLUMBING
J 2
(-1750 1700);
DISPLAY 1.234043 (-1750 1700);
PAINT GREEN (-1750 1700);
DISPLAY INVISIBLE (-1750 1700);
FORCEPROP 1 LAST HDL_TAP TRUE
J 2
(-2075 1625);
DISPLAY 1.234043 (-2075 1625);
PAINT GREEN (-2075 1625);
DISPLAY INVISIBLE (-2075 1625);
FORCEPROP 1 LAST PATH I108
J 2
(-1750 1750);
DISPLAY 0.936170 (-1750 1750);
PAINT GREEN (-1750 1750);
DISPLAY INVISIBLE (-1750 1750);
FORCEADD TAP..6
R 2
(-1750 1850);
FORCEPROP 3 LASTPIN (-1800 1850) SIG_NAME M_L_DQ<3>
J 0
(-1790 1860);
DISPLAY 0.659574 (-1790 1860);
PAINT MONO (-1790 1860);
DISPLAY INVISIBLE (-1790 1860);
FORCEPROP 1 LASTPIN (-1800 1850) BN 3
J 2
(-1750 1860);
DISPLAY 0.617021 (-1750 1860);
PAINT PINK (-1750 1860);
FORCEPROP 2 LAST CDS_LIB mstr_standard
J 2
(-1750 1850);
DISPLAY 0.787234 (-1750 1850);
PAINT MONO (-1750 1850);
DISPLAY INVISIBLE (-1750 1850);
FORCEPROP 1 LAST BODY_TYPE PLUMBING
J 2
(-1750 1800);
DISPLAY 1.234043 (-1750 1800);
PAINT GREEN (-1750 1800);
DISPLAY INVISIBLE (-1750 1800);
FORCEPROP 1 LAST HDL_TAP TRUE
J 2
(-2075 1725);
DISPLAY 1.234043 (-2075 1725);
PAINT GREEN (-2075 1725);
DISPLAY INVISIBLE (-2075 1725);
FORCEPROP 1 LAST PATH I109
J 2
(-1750 1850);
DISPLAY 0.936170 (-1750 1850);
PAINT GREEN (-1750 1850);
DISPLAY INVISIBLE (-1750 1850);
FORCEADD TAP..6
R 2
(700 4950);
FORCEPROP 3 LASTPIN (650 4950) SIG_NAME M_L_DQS_DP<15>
J 0
(660 4960);
DISPLAY 0.659574 (660 4960);
PAINT MONO (660 4960);
DISPLAY INVISIBLE (660 4960);
FORCEPROP 1 LASTPIN (650 4950) BN 15
J 2
(700 4960);
DISPLAY 0.617021 (700 4960);
PAINT PINK (700 4960);
FORCEPROP 2 LAST CDS_LIB mstr_standard
J 0
(700 4950);
DISPLAY 0.787234 (700 4950);
PAINT MONO (700 4950);
DISPLAY INVISIBLE (700 4950);
FORCEPROP 1 LAST BODY_TYPE PLUMBING
J 2
(700 4900);
DISPLAY 1.234043 (700 4900);
PAINT GREEN (700 4900);
DISPLAY INVISIBLE (700 4900);
FORCEPROP 1 LAST HDL_TAP TRUE
J 2
(375 4825);
DISPLAY 1.234043 (375 4825);
PAINT GREEN (375 4825);
DISPLAY INVISIBLE (375 4825);
FORCEPROP 1 LAST PATH I11
J 2
(700 4950);
DISPLAY 0.936170 (700 4950);
PAINT GREEN (700 4950);
DISPLAY INVISIBLE (700 4950);
FORCEADD TAP..6
R 2
(-1750 1800);
FORCEPROP 3 LASTPIN (-1800 1800) SIG_NAME M_L_DQ<0>
J 0
(-1790 1810);
DISPLAY 0.659574 (-1790 1810);
PAINT MONO (-1790 1810);
DISPLAY INVISIBLE (-1790 1810);
FORCEPROP 1 LASTPIN (-1800 1800) BN 0
J 2
(-1750 1810);
DISPLAY 0.617021 (-1750 1810);
PAINT PINK (-1750 1810);
FORCEPROP 2 LAST CDS_LIB mstr_standard
J 2
(-1750 1800);
DISPLAY 0.787234 (-1750 1800);
PAINT MONO (-1750 1800);
DISPLAY INVISIBLE (-1750 1800);
FORCEPROP 1 LAST BODY_TYPE PLUMBING
J 2
(-1750 1750);
DISPLAY 1.234043 (-1750 1750);
PAINT GREEN (-1750 1750);
DISPLAY INVISIBLE (-1750 1750);
FORCEPROP 1 LAST HDL_TAP TRUE
J 2
(-2075 1675);
DISPLAY 1.234043 (-2075 1675);
PAINT GREEN (-2075 1675);
DISPLAY INVISIBLE (-2075 1675);
FORCEPROP 1 LAST PATH I110
J 2
(-1750 1800);
DISPLAY 0.936170 (-1750 1800);
PAINT GREEN (-1750 1800);
DISPLAY INVISIBLE (-1750 1800);
FORCEADD SCONN288_H44441004..1
(-2500 3250);
FORCEPROP 1 LAST LOCATION J1A2
J 0
(-2950 5150);
DISPLAY 0.617021 (-2950 5150);
PAINT AQUA (-2950 5150);
FORCEPROP 1 LAST PART_NUMBER H44441-004
J 0
(-2950 1250);
DISPLAY 0.617021 (-2950 1250);
PAINT BLUE (-2950 1250);
FORCEPROP 1 LAST MATERIAL SCONN
J 0
(-2950 5100);
DISPLAY 0.617021 (-2950 5100);
PAINT SKYBLUE (-2950 5100);
FORCEPROP 2 LASTPIN (-3000 1750) $PN 146
J 2
(-3010 1760);
DISPLAY 0.617021 (-3010 1760);
PAINT ORANGE (-3010 1760);
FORCEPROP 2 LASTPIN (-3000 2100) $PN 284
J 2
(-3010 2110);
DISPLAY 0.617021 (-3010 2110);
PAINT ORANGE (-3010 2110);
FORCEPROP 2 LASTPIN (-3000 1900) $PN 285
J 2
(-3010 1910);
DISPLAY 0.617021 (-3010 1910);
PAINT ORANGE (-3010 1910);
FORCEPROP 2 LASTPIN (-3000 1850) $PN 141
J 2
(-3010 1860);
DISPLAY 0.617021 (-3010 1860);
PAINT ORANGE (-3010 1860);
FORCEPROP 2 LASTPIN (-3000 1450) $PN 230
J 2
(-3010 1460);
DISPLAY 0.617021 (-3010 1460);
PAINT ORANGE (-3010 1460);
FORCEPROP 2 LASTPIN (-3000 2050) $PN 238
J 2
(-3010 2060);
DISPLAY 0.617021 (-3010 2060);
PAINT ORANGE (-3010 2060);
FORCEPROP 2 LASTPIN (-3000 2000) $PN 140
J 2
(-3010 2010);
DISPLAY 0.617021 (-3010 2010);
PAINT ORANGE (-3010 2010);
FORCEPROP 2 LASTPIN (-3000 1950) $PN 139
J 2
(-3010 1960);
DISPLAY 0.617021 (-3010 1960);
PAINT ORANGE (-3010 1960);
FORCEPROP 2 LASTPIN (-3000 3400) $PN 237
J 2
(-3010 3410);
DISPLAY 0.617021 (-3010 3410);
PAINT ORANGE (-3010 3410);
FORCEPROP 2 LASTPIN (-3000 3350) $PN 93
J 2
(-3010 3360);
DISPLAY 0.617021 (-3010 3360);
PAINT ORANGE (-3010 3360);
FORCEPROP 2 LASTPIN (-3000 3300) $PN 89
J 2
(-3010 3310);
DISPLAY 0.617021 (-3010 3310);
PAINT ORANGE (-3010 3310);
FORCEPROP 2 LASTPIN (-3000 3250) $PN 84
J 2
(-3010 3260);
DISPLAY 0.617021 (-3010 3260);
PAINT ORANGE (-3010 3260);
FORCEPROP 2 LASTPIN (-3000 1650) $PN 144
J 2
(-3010 1660);
DISPLAY 0.617021 (-3010 1660);
PAINT ORANGE (-3010 1660);
FORCEPROP 2 LASTPIN (-3000 1600) $PN 227
J 2
(-3010 1610);
DISPLAY 0.617021 (-3010 1610);
PAINT ORANGE (-3010 1610);
FORCEPROP 2 LASTPIN (-3000 1550) $PN 205
J 2
(-3010 1560);
DISPLAY 0.617021 (-3010 1560);
PAINT ORANGE (-3010 1560);
FORCEPROP 2 LASTPIN (-3000 2350) $PN 58
J 2
(-3010 2360);
DISPLAY 0.617021 (-3010 2360);
PAINT ORANGE (-3010 2360);
FORCEPROP 2 LASTPIN (-3000 2400) $PN 222
J 2
(-3010 2410);
DISPLAY 0.617021 (-3010 2410);
PAINT ORANGE (-3010 2410);
FORCEPROP 2 LASTPIN (-3000 3000) $PN 91
J 2
(-3010 3010);
DISPLAY 0.617021 (-3010 3010);
PAINT ORANGE (-3010 3010);
FORCEPROP 2 LASTPIN (-3000 2950) $PN 87
J 2
(-3010 2960);
DISPLAY 0.617021 (-3010 2960);
PAINT ORANGE (-3010 2960);
FORCEPROP 2 LASTPIN (-3000 2300) $PN 78
J 2
(-3010 2310);
DISPLAY 0.617021 (-3010 2310);
PAINT ORANGE (-3010 2310);
FORCEPROP 2 LASTPIN (-2000 4900) $PN 280
J 0
(-1990 4910);
DISPLAY 0.617021 (-1990 4910);
PAINT ORANGE (-1990 4910);
FORCEPROP 2 LASTPIN (-2000 4850) $PN 135
J 0
(-1990 4860);
DISPLAY 0.617021 (-1990 4860);
PAINT ORANGE (-1990 4860);
FORCEPROP 2 LASTPIN (-2000 4800) $PN 273
J 0
(-1990 4810);
DISPLAY 0.617021 (-1990 4810);
PAINT ORANGE (-1990 4810);
FORCEPROP 2 LASTPIN (-2000 4750) $PN 128
J 0
(-1990 4760);
DISPLAY 0.617021 (-1990 4760);
PAINT ORANGE (-1990 4760);
FORCEPROP 2 LASTPIN (-2000 4700) $PN 282
J 0
(-1990 4710);
DISPLAY 0.617021 (-1990 4710);
PAINT ORANGE (-1990 4710);
FORCEPROP 2 LASTPIN (-2000 4650) $PN 137
J 0
(-1990 4660);
DISPLAY 0.617021 (-1990 4660);
PAINT ORANGE (-1990 4660);
FORCEPROP 2 LASTPIN (-2000 4600) $PN 275
J 0
(-1990 4610);
DISPLAY 0.617021 (-1990 4610);
PAINT ORANGE (-1990 4610);
FORCEPROP 2 LASTPIN (-2000 4550) $PN 130
J 0
(-1990 4560);
DISPLAY 0.617021 (-1990 4560);
PAINT ORANGE (-1990 4560);
FORCEPROP 2 LASTPIN (-2000 4500) $PN 269
J 0
(-1990 4510);
DISPLAY 0.617021 (-1990 4510);
PAINT ORANGE (-1990 4510);
FORCEPROP 2 LASTPIN (-2000 4450) $PN 124
J 0
(-1990 4460);
DISPLAY 0.617021 (-1990 4460);
PAINT ORANGE (-1990 4460);
FORCEPROP 2 LASTPIN (-2000 4400) $PN 262
J 0
(-1990 4410);
DISPLAY 0.617021 (-1990 4410);
PAINT ORANGE (-1990 4410);
FORCEPROP 2 LASTPIN (-2000 4350) $PN 117
J 0
(-1990 4360);
DISPLAY 0.617021 (-1990 4360);
PAINT ORANGE (-1990 4360);
FORCEPROP 2 LASTPIN (-2000 4300) $PN 271
J 0
(-1990 4310);
DISPLAY 0.617021 (-1990 4310);
PAINT ORANGE (-1990 4310);
FORCEPROP 2 LASTPIN (-2000 4250) $PN 126
J 0
(-1990 4260);
DISPLAY 0.617021 (-1990 4260);
PAINT ORANGE (-1990 4260);
FORCEPROP 2 LASTPIN (-2000 4200) $PN 264
J 0
(-1990 4210);
DISPLAY 0.617021 (-1990 4210);
PAINT ORANGE (-1990 4210);
FORCEPROP 2 LASTPIN (-2000 4150) $PN 119
J 0
(-1990 4160);
DISPLAY 0.617021 (-1990 4160);
PAINT ORANGE (-1990 4160);
FORCEPROP 2 LASTPIN (-2000 4100) $PN 258
J 0
(-1990 4110);
DISPLAY 0.617021 (-1990 4110);
PAINT ORANGE (-1990 4110);
FORCEPROP 2 LASTPIN (-2000 4050) $PN 113
J 0
(-1990 4060);
DISPLAY 0.617021 (-1990 4060);
PAINT ORANGE (-1990 4060);
FORCEPROP 2 LASTPIN (-2000 4000) $PN 251
J 0
(-1990 4010);
DISPLAY 0.617021 (-1990 4010);
PAINT ORANGE (-1990 4010);
FORCEPROP 2 LASTPIN (-2000 3950) $PN 106
J 0
(-1990 3960);
DISPLAY 0.617021 (-1990 3960);
PAINT ORANGE (-1990 3960);
FORCEPROP 2 LASTPIN (-2000 3900) $PN 260
J 0
(-1990 3910);
DISPLAY 0.617021 (-1990 3910);
PAINT ORANGE (-1990 3910);
FORCEPROP 2 LASTPIN (-2000 3850) $PN 115
J 0
(-1990 3860);
DISPLAY 0.617021 (-1990 3860);
PAINT ORANGE (-1990 3860);
FORCEPROP 2 LASTPIN (-2000 3800) $PN 253
J 0
(-1990 3810);
DISPLAY 0.617021 (-1990 3810);
PAINT ORANGE (-1990 3810);
FORCEPROP 2 LASTPIN (-2000 3750) $PN 108
J 0
(-1990 3760);
DISPLAY 0.617021 (-1990 3760);
PAINT ORANGE (-1990 3760);
FORCEPROP 2 LASTPIN (-2000 3700) $PN 247
J 0
(-1990 3710);
DISPLAY 0.617021 (-1990 3710);
PAINT ORANGE (-1990 3710);
FORCEPROP 2 LASTPIN (-2000 3650) $PN 102
J 0
(-1990 3660);
DISPLAY 0.617021 (-1990 3660);
PAINT ORANGE (-1990 3660);
FORCEPROP 2 LASTPIN (-2000 3600) $PN 240
J 0
(-1990 3610);
DISPLAY 0.617021 (-1990 3610);
PAINT ORANGE (-1990 3610);
FORCEPROP 2 LASTPIN (-2000 3550) $PN 95
J 0
(-1990 3560);
DISPLAY 0.617021 (-1990 3560);
PAINT ORANGE (-1990 3560);
FORCEPROP 2 LASTPIN (-2000 3500) $PN 249
J 0
(-1990 3510);
DISPLAY 0.617021 (-1990 3510);
PAINT ORANGE (-1990 3510);
FORCEPROP 2 LASTPIN (-2000 3450) $PN 104
J 0
(-1990 3460);
DISPLAY 0.617021 (-1990 3460);
PAINT ORANGE (-1990 3460);
FORCEPROP 2 LASTPIN (-2000 3400) $PN 242
J 0
(-1990 3410);
DISPLAY 0.617021 (-1990 3410);
PAINT ORANGE (-1990 3410);
FORCEPROP 2 LASTPIN (-2000 3350) $PN 97
J 0
(-1990 3360);
DISPLAY 0.617021 (-1990 3360);
PAINT ORANGE (-1990 3360);
FORCEPROP 2 LASTPIN (-2000 3300) $PN 188
J 0
(-1990 3310);
DISPLAY 0.617021 (-1990 3310);
PAINT ORANGE (-1990 3310);
FORCEPROP 2 LASTPIN (-2000 3250) $PN 43
J 0
(-1990 3260);
DISPLAY 0.617021 (-1990 3260);
PAINT ORANGE (-1990 3260);
FORCEPROP 2 LASTPIN (-2000 3200) $PN 181
J 0
(-1990 3210);
DISPLAY 0.617021 (-1990 3210);
PAINT ORANGE (-1990 3210);
FORCEPROP 2 LASTPIN (-2000 3150) $PN 36
J 0
(-1990 3160);
DISPLAY 0.617021 (-1990 3160);
PAINT ORANGE (-1990 3160);
FORCEPROP 2 LASTPIN (-2000 3100) $PN 190
J 0
(-1990 3110);
DISPLAY 0.617021 (-1990 3110);
PAINT ORANGE (-1990 3110);
FORCEPROP 2 LASTPIN (-2000 3050) $PN 45
J 0
(-1990 3060);
DISPLAY 0.617021 (-1990 3060);
PAINT ORANGE (-1990 3060);
FORCEPROP 2 LASTPIN (-2000 3000) $PN 183
J 0
(-1990 3010);
DISPLAY 0.617021 (-1990 3010);
PAINT ORANGE (-1990 3010);
FORCEPROP 2 LASTPIN (-2000 2950) $PN 38
J 0
(-1990 2960);
DISPLAY 0.617021 (-1990 2960);
PAINT ORANGE (-1990 2960);
FORCEPROP 2 LASTPIN (-2000 2900) $PN 177
J 0
(-1990 2910);
DISPLAY 0.617021 (-1990 2910);
PAINT ORANGE (-1990 2910);
FORCEPROP 2 LASTPIN (-2000 2850) $PN 32
J 0
(-1990 2860);
DISPLAY 0.617021 (-1990 2860);
PAINT ORANGE (-1990 2860);
FORCEPROP 2 LASTPIN (-2000 2800) $PN 170
J 0
(-1990 2810);
DISPLAY 0.617021 (-1990 2810);
PAINT ORANGE (-1990 2810);
FORCEPROP 2 LASTPIN (-2000 2750) $PN 25
J 0
(-1990 2760);
DISPLAY 0.617021 (-1990 2760);
PAINT ORANGE (-1990 2760);
FORCEPROP 2 LASTPIN (-2000 2700) $PN 179
J 0
(-1990 2710);
DISPLAY 0.617021 (-1990 2710);
PAINT ORANGE (-1990 2710);
FORCEPROP 2 LASTPIN (-2000 2650) $PN 34
J 0
(-1990 2660);
DISPLAY 0.617021 (-1990 2660);
PAINT ORANGE (-1990 2660);
FORCEPROP 2 LASTPIN (-2000 2600) $PN 172
J 0
(-1990 2610);
DISPLAY 0.617021 (-1990 2610);
PAINT ORANGE (-1990 2610);
FORCEPROP 2 LASTPIN (-2000 2550) $PN 27
J 0
(-1990 2560);
DISPLAY 0.617021 (-1990 2560);
PAINT ORANGE (-1990 2560);
FORCEPROP 2 LASTPIN (-2000 2500) $PN 166
J 0
(-1990 2510);
DISPLAY 0.617021 (-1990 2510);
PAINT ORANGE (-1990 2510);
FORCEPROP 2 LASTPIN (-2000 2450) $PN 21
J 0
(-1990 2460);
DISPLAY 0.617021 (-1990 2460);
PAINT ORANGE (-1990 2460);
FORCEPROP 2 LASTPIN (-2000 2400) $PN 159
J 0
(-1990 2410);
DISPLAY 0.617021 (-1990 2410);
PAINT ORANGE (-1990 2410);
FORCEPROP 2 LASTPIN (-2000 2350) $PN 14
J 0
(-1990 2360);
DISPLAY 0.617021 (-1990 2360);
PAINT ORANGE (-1990 2360);
FORCEPROP 2 LASTPIN (-2000 2300) $PN 168
J 0
(-1990 2310);
DISPLAY 0.617021 (-1990 2310);
PAINT ORANGE (-1990 2310);
FORCEPROP 2 LASTPIN (-2000 2250) $PN 23
J 0
(-1990 2260);
DISPLAY 0.617021 (-1990 2260);
PAINT ORANGE (-1990 2260);
FORCEPROP 2 LASTPIN (-2000 2200) $PN 161
J 0
(-1990 2210);
DISPLAY 0.617021 (-1990 2210);
PAINT ORANGE (-1990 2210);
FORCEPROP 2 LASTPIN (-2000 2150) $PN 16
J 0
(-1990 2160);
DISPLAY 0.617021 (-1990 2160);
PAINT ORANGE (-1990 2160);
FORCEPROP 2 LASTPIN (-2000 2100) $PN 155
J 0
(-1990 2110);
DISPLAY 0.617021 (-1990 2110);
PAINT ORANGE (-1990 2110);
FORCEPROP 2 LASTPIN (-2000 2050) $PN 10
J 0
(-1990 2060);
DISPLAY 0.617021 (-1990 2060);
PAINT ORANGE (-1990 2060);
FORCEPROP 2 LASTPIN (-2000 2000) $PN 148
J 0
(-1990 2010);
DISPLAY 0.617021 (-1990 2010);
PAINT ORANGE (-1990 2010);
FORCEPROP 2 LASTPIN (-2000 1950) $PN 3
J 0
(-1990 1960);
DISPLAY 0.617021 (-1990 1960);
PAINT ORANGE (-1990 1960);
FORCEPROP 2 LASTPIN (-2000 1900) $PN 157
J 0
(-1990 1910);
DISPLAY 0.617021 (-1990 1910);
PAINT ORANGE (-1990 1910);
FORCEPROP 2 LASTPIN (-2000 1850) $PN 12
J 0
(-1990 1860);
DISPLAY 0.617021 (-1990 1860);
PAINT ORANGE (-1990 1860);
FORCEPROP 2 LASTPIN (-2000 1800) $PN 150
J 0
(-1990 1810);
DISPLAY 0.617021 (-1990 1810);
PAINT ORANGE (-1990 1810);
FORCEPROP 2 LASTPIN (-2000 1750) $PN 5
J 0
(-1990 1760);
DISPLAY 0.617021 (-1990 1760);
PAINT ORANGE (-1990 1760);
FORCEPROP 2 LASTPIN (-3000 3150) $PN 203
J 2
(-3010 3160);
DISPLAY 0.617021 (-3010 3160);
PAINT ORANGE (-3010 3160);
FORCEPROP 2 LASTPIN (-3000 3100) $PN 60
J 2
(-3010 3110);
DISPLAY 0.617021 (-3010 3110);
PAINT ORANGE (-3010 3110);
FORCEPROP 2 LASTPIN (-3000 3700) $PN 218
J 2
(-3010 3710);
DISPLAY 0.617021 (-3010 3710);
PAINT ORANGE (-3010 3710);
FORCEPROP 2 LASTPIN (-3000 3650) $PN 219
J 2
(-3010 3660);
DISPLAY 0.617021 (-3010 3660);
PAINT ORANGE (-3010 3660);
FORCEPROP 2 LASTPIN (-3000 3600) $PN 74
J 2
(-3010 3610);
DISPLAY 0.617021 (-3010 3610);
PAINT ORANGE (-3010 3610);
FORCEPROP 2 LASTPIN (-3000 3550) $PN 75
J 2
(-3010 3560);
DISPLAY 0.617021 (-3010 3560);
PAINT ORANGE (-3010 3560);
FORCEPROP 2 LASTPIN (-3000 2850) $PN 199
J 2
(-3010 2860);
DISPLAY 0.617021 (-3010 2860);
PAINT ORANGE (-3010 2860);
FORCEPROP 2 LASTPIN (-3000 2800) $PN 54
J 2
(-3010 2810);
DISPLAY 0.617021 (-3010 2810);
PAINT ORANGE (-3010 2810);
FORCEPROP 2 LASTPIN (-3000 2750) $PN 192
J 2
(-3010 2760);
DISPLAY 0.617021 (-3010 2760);
PAINT ORANGE (-3010 2760);
FORCEPROP 2 LASTPIN (-3000 2700) $PN 47
J 2
(-3010 2710);
DISPLAY 0.617021 (-3010 2710);
PAINT ORANGE (-3010 2710);
FORCEPROP 2 LASTPIN (-3000 2650) $PN 201
J 2
(-3010 2660);
DISPLAY 0.617021 (-3010 2660);
PAINT ORANGE (-3010 2660);
FORCEPROP 2 LASTPIN (-3000 2600) $PN 56
J 2
(-3010 2610);
DISPLAY 0.617021 (-3010 2610);
PAINT ORANGE (-3010 2610);
FORCEPROP 2 LASTPIN (-3000 2550) $PN 194
J 2
(-3010 2560);
DISPLAY 0.617021 (-3010 2560);
PAINT ORANGE (-3010 2560);
FORCEPROP 2 LASTPIN (-3000 2500) $PN 49
J 2
(-3010 2510);
DISPLAY 0.617021 (-3010 2510);
PAINT ORANGE (-3010 2510);
FORCEPROP 2 LASTPIN (-3000 3450) $PN 235
J 2
(-3010 3460);
DISPLAY 0.617021 (-3010 3460);
PAINT ORANGE (-3010 3460);
FORCEPROP 2 LASTPIN (-3000 3850) $PN 207
J 2
(-3010 3860);
DISPLAY 0.617021 (-3010 3860);
PAINT ORANGE (-3010 3860);
FORCEPROP 2 LASTPIN (-3000 3800) $PN 63
J 2
(-3010 3810);
DISPLAY 0.617021 (-3010 3810);
PAINT ORANGE (-3010 3810);
FORCEPROP 2 LASTPIN (-3000 3950) $PN 224
J 2
(-3010 3960);
DISPLAY 0.617021 (-3010 3960);
PAINT ORANGE (-3010 3960);
FORCEPROP 2 LASTPIN (-3000 3900) $PN 81
J 2
(-3010 3910);
DISPLAY 0.617021 (-3010 3910);
PAINT ORANGE (-3010 3910);
FORCEPROP 2 LASTPIN (-3000 2250) $PN 208
J 2
(-3010 2260);
DISPLAY 0.617021 (-3010 2260);
PAINT ORANGE (-3010 2260);
FORCEPROP 2 LASTPIN (-3000 2200) $PN 62
J 2
(-3010 2210);
DISPLAY 0.617021 (-3010 2210);
PAINT ORANGE (-3010 2210);
FORCEPROP 2 LASTPIN (-3000 4900) $PN 234
J 2
(-3010 4910);
DISPLAY 0.617021 (-3010 4910);
PAINT ORANGE (-3010 4910);
FORCEPROP 2 LASTPIN (-3000 4850) $PN 82
J 2
(-3010 4860);
DISPLAY 0.617021 (-3010 4860);
PAINT ORANGE (-3010 4860);
FORCEPROP 2 LASTPIN (-3000 4800) $PN 86
J 2
(-3010 4810);
DISPLAY 0.617021 (-3010 4810);
PAINT ORANGE (-3010 4810);
FORCEPROP 2 LASTPIN (-3000 4750) $PN 228
J 2
(-3010 4760);
DISPLAY 0.617021 (-3010 4760);
PAINT ORANGE (-3010 4760);
FORCEPROP 2 LASTPIN (-3000 4700) $PN 232
J 2
(-3010 4710);
DISPLAY 0.617021 (-3010 4710);
PAINT ORANGE (-3010 4710);
FORCEPROP 2 LASTPIN (-3000 4650) $PN 65
J 2
(-3010 4660);
DISPLAY 0.617021 (-3010 4660);
PAINT ORANGE (-3010 4660);
FORCEPROP 2 LASTPIN (-3000 4600) $PN 210
J 2
(-3010 4610);
DISPLAY 0.617021 (-3010 4610);
PAINT ORANGE (-3010 4610);
FORCEPROP 2 LASTPIN (-3000 4550) $PN 225
J 2
(-3010 4560);
DISPLAY 0.617021 (-3010 4560);
PAINT ORANGE (-3010 4560);
FORCEPROP 2 LASTPIN (-3000 4500) $PN 66
J 2
(-3010 4510);
DISPLAY 0.617021 (-3010 4510);
PAINT ORANGE (-3010 4510);
FORCEPROP 2 LASTPIN (-3000 4450) $PN 68
J 2
(-3010 4460);
DISPLAY 0.617021 (-3010 4460);
PAINT ORANGE (-3010 4460);
FORCEPROP 2 LASTPIN (-3000 4400) $PN 211
J 2
(-3010 4410);
DISPLAY 0.617021 (-3010 4410);
PAINT ORANGE (-3010 4410);
FORCEPROP 2 LASTPIN (-3000 4350) $PN 69
J 2
(-3010 4360);
DISPLAY 0.617021 (-3010 4360);
PAINT ORANGE (-3010 4360);
FORCEPROP 2 LASTPIN (-3000 4300) $PN 213
J 2
(-3010 4310);
DISPLAY 0.617021 (-3010 4310);
PAINT ORANGE (-3010 4310);
FORCEPROP 2 LASTPIN (-3000 4250) $PN 214
J 2
(-3010 4260);
DISPLAY 0.617021 (-3010 4260);
PAINT ORANGE (-3010 4260);
FORCEPROP 2 LASTPIN (-3000 4200) $PN 71
J 2
(-3010 4210);
DISPLAY 0.617021 (-3010 4210);
PAINT ORANGE (-3010 4210);
FORCEPROP 2 LASTPIN (-3000 4150) $PN 216
J 2
(-3010 4160);
DISPLAY 0.617021 (-3010 4160);
PAINT ORANGE (-3010 4160);
FORCEPROP 2 LASTPIN (-3000 4100) $PN 72
J 2
(-3010 4110);
DISPLAY 0.617021 (-3010 4110);
PAINT ORANGE (-3010 4110);
FORCEPROP 2 LASTPIN (-3000 4050) $PN 79
J 2
(-3010 4060);
DISPLAY 0.617021 (-3010 4060);
PAINT ORANGE (-3010 4060);
FORCEPROP 1 LAST PACK_TYPE PIP
J 0
(-2950 5200);
PAINT SKYBLUE (-2950 5200);
DISPLAY INVISIBLE (-2950 5200);
FORCEPROP 2 LAST BOM_COST MEM
J 0
(-2500 3250);
PAINT ORANGE (-2500 3250);
DISPLAY INVISIBLE (-2500 3250);
FORCEPROP 2 LAST CDS_LIB mstr_sconn
J 0
(-2500 3250);
PAINT ORANGE (-2500 3250);
DISPLAY INVISIBLE (-2500 3250);
FORCEPROP 2 LAST SEC_TYPE PIP
J 0
(-2950 5200);
DISPLAY 1.021277 (-2950 5200);
PAINT ORANGE (-2950 5200);
DISPLAY INVISIBLE (-2950 5200);
FORCEPROP 2 LAST SEC 1
J 0
(-2950 5200);
DISPLAY 0.680851 (-2950 5200);
PAINT MONO (-2950 5200);
DISPLAY INVISIBLE (-2950 5200);
FORCEPROP 2 LAST CDS_LOCATION J1A2
J 0
(-2950 5150);
DISPLAY 0.617021 (-2950 5150);
PAINT AQUA (-2950 5150);
DISPLAY INVISIBLE (-2950 5150);
FORCEPROP 1 LAST PATH I111
J 0
(-2500 5100);
PAINT GREEN (-2500 5100);
DISPLAY INVISIBLE (-2500 5100);
FORCEPROP 2 LAST ROOM DDR4_CH_L
J 0
(-2500 3250);
PAINT ORANGE (-2500 3250);
DISPLAY INVISIBLE (-2500 3250);
FORCEADD TAP..6
(-3250 4850);
FORCEPROP 3 LASTPIN (-3200 4850) SIG_NAME M_L_MA<16>
J 0
(-3190 4860);
DISPLAY 0.659574 (-3190 4860);
PAINT MONO (-3190 4860);
DISPLAY INVISIBLE (-3190 4860);
FORCEPROP 1 LASTPIN (-3200 4850) BN 16
J 0
(-3250 4860);
DISPLAY 0.617021 (-3250 4860);
PAINT PINK (-3250 4860);
FORCEPROP 2 LAST CDS_LIB mstr_standard
J 2
(-3250 4850);
DISPLAY 0.787234 (-3250 4850);
PAINT MONO (-3250 4850);
DISPLAY INVISIBLE (-3250 4850);
FORCEPROP 1 LAST BODY_TYPE PLUMBING
J 0
(-3250 4800);
DISPLAY 1.234043 (-3250 4800);
PAINT GREEN (-3250 4800);
DISPLAY INVISIBLE (-3250 4800);
FORCEPROP 1 LAST HDL_TAP TRUE
J 0
(-2925 4725);
DISPLAY 1.234043 (-2925 4725);
PAINT GREEN (-2925 4725);
DISPLAY INVISIBLE (-2925 4725);
FORCEPROP 1 LAST PATH I112
J 0
(-3250 4850);
DISPLAY 0.936170 (-3250 4850);
PAINT GREEN (-3250 4850);
DISPLAY INVISIBLE (-3250 4850);
FORCEADD TAP..6
(-3250 4900);
FORCEPROP 3 LASTPIN (-3200 4900) SIG_NAME M_L_MA<17>
J 0
(-3190 4910);
DISPLAY 0.659574 (-3190 4910);
PAINT MONO (-3190 4910);
DISPLAY INVISIBLE (-3190 4910);
FORCEPROP 1 LASTPIN (-3200 4900) BN 17
J 0
(-3250 4910);
DISPLAY 0.617021 (-3250 4910);
PAINT PINK (-3250 4910);
FORCEPROP 2 LAST CDS_LIB mstr_standard
J 0
(-3250 4900);
DISPLAY 0.787234 (-3250 4900);
PAINT MONO (-3250 4900);
DISPLAY INVISIBLE (-3250 4900);
FORCEPROP 1 LAST BODY_TYPE PLUMBING
J 0
(-3250 4850);
DISPLAY 1.234043 (-3250 4850);
PAINT GREEN (-3250 4850);
DISPLAY INVISIBLE (-3250 4850);
FORCEPROP 1 LAST HDL_TAP TRUE
J 0
(-2925 4775);
DISPLAY 1.234043 (-2925 4775);
PAINT GREEN (-2925 4775);
DISPLAY INVISIBLE (-2925 4775);
FORCEPROP 1 LAST PATH I113
J 0
(-3250 4900);
DISPLAY 0.936170 (-3250 4900);
PAINT GREEN (-3250 4900);
DISPLAY INVISIBLE (-3250 4900);
FORCEADD TAP..6
(-3250 4800);
FORCEPROP 3 LASTPIN (-3200 4800) SIG_NAME M_L_MA<15>
J 0
(-3190 4810);
DISPLAY 0.659574 (-3190 4810);
PAINT MONO (-3190 4810);
DISPLAY INVISIBLE (-3190 4810);
FORCEPROP 1 LASTPIN (-3200 4800) BN 15
J 0
(-3250 4810);
DISPLAY 0.617021 (-3250 4810);
PAINT PINK (-3250 4810);
FORCEPROP 2 LAST CDS_LIB mstr_standard
J 2
(-3250 4800);
DISPLAY 0.787234 (-3250 4800);
PAINT MONO (-3250 4800);
DISPLAY INVISIBLE (-3250 4800);
FORCEPROP 1 LAST BODY_TYPE PLUMBING
J 0
(-3250 4750);
DISPLAY 1.234043 (-3250 4750);
PAINT GREEN (-3250 4750);
DISPLAY INVISIBLE (-3250 4750);
FORCEPROP 1 LAST HDL_TAP TRUE
J 0
(-2925 4675);
DISPLAY 1.234043 (-2925 4675);
PAINT GREEN (-2925 4675);
DISPLAY INVISIBLE (-2925 4675);
FORCEPROP 1 LAST PATH I114
J 0
(-3250 4800);
DISPLAY 0.936170 (-3250 4800);
PAINT GREEN (-3250 4800);
DISPLAY INVISIBLE (-3250 4800);
FORCEADD TAP..6
(-3250 4750);
FORCEPROP 3 LASTPIN (-3200 4750) SIG_NAME M_L_MA<14>
J 0
(-3190 4760);
DISPLAY 0.659574 (-3190 4760);
PAINT MONO (-3190 4760);
DISPLAY INVISIBLE (-3190 4760);
FORCEPROP 1 LASTPIN (-3200 4750) BN 14
J 0
(-3250 4760);
DISPLAY 0.617021 (-3250 4760);
PAINT PINK (-3250 4760);
FORCEPROP 2 LAST CDS_LIB mstr_standard
J 2
(-3250 4750);
DISPLAY 0.787234 (-3250 4750);
PAINT MONO (-3250 4750);
DISPLAY INVISIBLE (-3250 4750);
FORCEPROP 1 LAST BODY_TYPE PLUMBING
J 0
(-3250 4700);
DISPLAY 1.234043 (-3250 4700);
PAINT GREEN (-3250 4700);
DISPLAY INVISIBLE (-3250 4700);
FORCEPROP 1 LAST HDL_TAP TRUE
J 0
(-2925 4625);
DISPLAY 1.234043 (-2925 4625);
PAINT GREEN (-2925 4625);
DISPLAY INVISIBLE (-2925 4625);
FORCEPROP 1 LAST PATH I115
J 0
(-3250 4750);
DISPLAY 0.936170 (-3250 4750);
PAINT GREEN (-3250 4750);
DISPLAY INVISIBLE (-3250 4750);
FORCEADD TAP..6
(-3250 4700);
FORCEPROP 3 LASTPIN (-3200 4700) SIG_NAME M_L_MA<13>
J 0
(-3190 4710);
DISPLAY 0.659574 (-3190 4710);
PAINT MONO (-3190 4710);
DISPLAY INVISIBLE (-3190 4710);
FORCEPROP 1 LASTPIN (-3200 4700) BN 13
J 0
(-3250 4710);
DISPLAY 0.617021 (-3250 4710);
PAINT PINK (-3250 4710);
FORCEPROP 2 LAST CDS_LIB mstr_standard
J 2
(-3250 4700);
DISPLAY 0.787234 (-3250 4700);
PAINT MONO (-3250 4700);
DISPLAY INVISIBLE (-3250 4700);
FORCEPROP 1 LAST BODY_TYPE PLUMBING
J 0
(-3250 4650);
DISPLAY 1.234043 (-3250 4650);
PAINT GREEN (-3250 4650);
DISPLAY INVISIBLE (-3250 4650);
FORCEPROP 1 LAST HDL_TAP TRUE
J 0
(-2925 4575);
DISPLAY 1.234043 (-2925 4575);
PAINT GREEN (-2925 4575);
DISPLAY INVISIBLE (-2925 4575);
FORCEPROP 1 LAST PATH I116
J 0
(-3250 4700);
DISPLAY 0.936170 (-3250 4700);
PAINT GREEN (-3250 4700);
DISPLAY INVISIBLE (-3250 4700);
FORCEADD TAP..6
(-3250 4650);
FORCEPROP 3 LASTPIN (-3200 4650) SIG_NAME M_L_MA<12>
J 0
(-3190 4660);
DISPLAY 0.659574 (-3190 4660);
PAINT MONO (-3190 4660);
DISPLAY INVISIBLE (-3190 4660);
FORCEPROP 1 LASTPIN (-3200 4650) BN 12
J 0
(-3250 4660);
DISPLAY 0.617021 (-3250 4660);
PAINT PINK (-3250 4660);
FORCEPROP 2 LAST CDS_LIB mstr_standard
J 2
(-3250 4650);
DISPLAY 0.787234 (-3250 4650);
PAINT MONO (-3250 4650);
DISPLAY INVISIBLE (-3250 4650);
FORCEPROP 1 LAST BODY_TYPE PLUMBING
J 0
(-3250 4600);
DISPLAY 1.234043 (-3250 4600);
PAINT GREEN (-3250 4600);
DISPLAY INVISIBLE (-3250 4600);
FORCEPROP 1 LAST HDL_TAP TRUE
J 0
(-2925 4525);
DISPLAY 1.234043 (-2925 4525);
PAINT GREEN (-2925 4525);
DISPLAY INVISIBLE (-2925 4525);
FORCEPROP 1 LAST PATH I117
J 0
(-3250 4650);
DISPLAY 0.936170 (-3250 4650);
PAINT GREEN (-3250 4650);
DISPLAY INVISIBLE (-3250 4650);
FORCEADD TAP..6
(-3250 4600);
FORCEPROP 3 LASTPIN (-3200 4600) SIG_NAME M_L_MA<11>
J 0
(-3190 4610);
DISPLAY 0.659574 (-3190 4610);
PAINT MONO (-3190 4610);
DISPLAY INVISIBLE (-3190 4610);
FORCEPROP 1 LASTPIN (-3200 4600) BN 11
J 0
(-3250 4610);
DISPLAY 0.617021 (-3250 4610);
PAINT PINK (-3250 4610);
FORCEPROP 2 LAST CDS_LIB mstr_standard
J 2
(-3250 4600);
DISPLAY 0.787234 (-3250 4600);
PAINT MONO (-3250 4600);
DISPLAY INVISIBLE (-3250 4600);
FORCEPROP 1 LAST BODY_TYPE PLUMBING
J 0
(-3250 4550);
DISPLAY 1.234043 (-3250 4550);
PAINT GREEN (-3250 4550);
DISPLAY INVISIBLE (-3250 4550);
FORCEPROP 1 LAST HDL_TAP TRUE
J 0
(-2925 4475);
DISPLAY 1.234043 (-2925 4475);
PAINT GREEN (-2925 4475);
DISPLAY INVISIBLE (-2925 4475);
FORCEPROP 1 LAST PATH I118
J 0
(-3250 4600);
DISPLAY 0.936170 (-3250 4600);
PAINT GREEN (-3250 4600);
DISPLAY INVISIBLE (-3250 4600);
FORCEADD TAP..6
(-3250 4550);
FORCEPROP 3 LASTPIN (-3200 4550) SIG_NAME M_L_MA<10>
J 0
(-3190 4560);
DISPLAY 0.659574 (-3190 4560);
PAINT MONO (-3190 4560);
DISPLAY INVISIBLE (-3190 4560);
FORCEPROP 1 LASTPIN (-3200 4550) BN 10
J 0
(-3250 4560);
DISPLAY 0.617021 (-3250 4560);
PAINT PINK (-3250 4560);
FORCEPROP 2 LAST CDS_LIB mstr_standard
J 2
(-3250 4550);
DISPLAY 0.787234 (-3250 4550);
PAINT MONO (-3250 4550);
DISPLAY INVISIBLE (-3250 4550);
FORCEPROP 1 LAST BODY_TYPE PLUMBING
J 0
(-3250 4500);
DISPLAY 1.234043 (-3250 4500);
PAINT GREEN (-3250 4500);
DISPLAY INVISIBLE (-3250 4500);
FORCEPROP 1 LAST HDL_TAP TRUE
J 0
(-2925 4425);
DISPLAY 1.234043 (-2925 4425);
PAINT GREEN (-2925 4425);
DISPLAY INVISIBLE (-2925 4425);
FORCEPROP 1 LAST PATH I119
J 0
(-3250 4550);
DISPLAY 0.936170 (-3250 4550);
PAINT GREEN (-3250 4550);
DISPLAY INVISIBLE (-3250 4550);
FORCEADD TAP..6
R 2
(700 5050);
FORCEPROP 3 LASTPIN (650 5050) SIG_NAME M_L_DQS_DP<16>
J 0
(660 5060);
DISPLAY 0.659574 (660 5060);
PAINT MONO (660 5060);
DISPLAY INVISIBLE (660 5060);
FORCEPROP 1 LASTPIN (650 5050) BN 16
J 2
(700 5060);
DISPLAY 0.617021 (700 5060);
PAINT PINK (700 5060);
FORCEPROP 2 LAST CDS_LIB mstr_standard
J 0
(700 5050);
DISPLAY 0.787234 (700 5050);
PAINT MONO (700 5050);
DISPLAY INVISIBLE (700 5050);
FORCEPROP 1 LAST BODY_TYPE PLUMBING
J 2
(700 5000);
DISPLAY 1.234043 (700 5000);
PAINT GREEN (700 5000);
DISPLAY INVISIBLE (700 5000);
FORCEPROP 1 LAST HDL_TAP TRUE
J 2
(375 4925);
DISPLAY 1.234043 (375 4925);
PAINT GREEN (375 4925);
DISPLAY INVISIBLE (375 4925);
FORCEPROP 1 LAST PATH I12
J 2
(700 5050);
DISPLAY 0.936170 (700 5050);
PAINT GREEN (700 5050);
DISPLAY INVISIBLE (700 5050);
FORCEADD TAP..6
(-3250 4500);
FORCEPROP 3 LASTPIN (-3200 4500) SIG_NAME M_L_MA<9>
J 0
(-3190 4510);
DISPLAY 0.659574 (-3190 4510);
PAINT MONO (-3190 4510);
DISPLAY INVISIBLE (-3190 4510);
FORCEPROP 1 LASTPIN (-3200 4500) BN 9
J 0
(-3250 4510);
DISPLAY 0.617021 (-3250 4510);
PAINT PINK (-3250 4510);
FORCEPROP 2 LAST CDS_LIB mstr_standard
J 2
(-3250 4500);
DISPLAY 0.787234 (-3250 4500);
PAINT MONO (-3250 4500);
DISPLAY INVISIBLE (-3250 4500);
FORCEPROP 1 LAST BODY_TYPE PLUMBING
J 0
(-3250 4450);
DISPLAY 1.234043 (-3250 4450);
PAINT GREEN (-3250 4450);
DISPLAY INVISIBLE (-3250 4450);
FORCEPROP 1 LAST HDL_TAP TRUE
J 0
(-2925 4375);
DISPLAY 1.234043 (-2925 4375);
PAINT GREEN (-2925 4375);
DISPLAY INVISIBLE (-2925 4375);
FORCEPROP 1 LAST PATH I120
J 0
(-3250 4500);
DISPLAY 0.936170 (-3250 4500);
PAINT GREEN (-3250 4500);
DISPLAY INVISIBLE (-3250 4500);
FORCEADD TAP..6
(-3250 4450);
FORCEPROP 3 LASTPIN (-3200 4450) SIG_NAME M_L_MA<8>
J 0
(-3190 4460);
DISPLAY 0.659574 (-3190 4460);
PAINT MONO (-3190 4460);
DISPLAY INVISIBLE (-3190 4460);
FORCEPROP 1 LASTPIN (-3200 4450) BN 8
J 0
(-3250 4460);
DISPLAY 0.617021 (-3250 4460);
PAINT PINK (-3250 4460);
FORCEPROP 2 LAST CDS_LIB mstr_standard
J 2
(-3250 4450);
DISPLAY 0.787234 (-3250 4450);
PAINT MONO (-3250 4450);
DISPLAY INVISIBLE (-3250 4450);
FORCEPROP 1 LAST BODY_TYPE PLUMBING
J 0
(-3250 4400);
DISPLAY 1.234043 (-3250 4400);
PAINT GREEN (-3250 4400);
DISPLAY INVISIBLE (-3250 4400);
FORCEPROP 1 LAST HDL_TAP TRUE
J 0
(-2925 4325);
DISPLAY 1.234043 (-2925 4325);
PAINT GREEN (-2925 4325);
DISPLAY INVISIBLE (-2925 4325);
FORCEPROP 1 LAST PATH I121
J 0
(-3250 4450);
DISPLAY 0.936170 (-3250 4450);
PAINT GREEN (-3250 4450);
DISPLAY INVISIBLE (-3250 4450);
FORCEADD TAP..6
(-3250 4400);
FORCEPROP 3 LASTPIN (-3200 4400) SIG_NAME M_L_MA<7>
J 0
(-3190 4410);
DISPLAY 0.659574 (-3190 4410);
PAINT MONO (-3190 4410);
DISPLAY INVISIBLE (-3190 4410);
FORCEPROP 1 LASTPIN (-3200 4400) BN 7
J 0
(-3250 4410);
DISPLAY 0.617021 (-3250 4410);
PAINT PINK (-3250 4410);
FORCEPROP 2 LAST CDS_LIB mstr_standard
J 2
(-3250 4400);
DISPLAY 0.787234 (-3250 4400);
PAINT MONO (-3250 4400);
DISPLAY INVISIBLE (-3250 4400);
FORCEPROP 1 LAST BODY_TYPE PLUMBING
J 0
(-3250 4350);
DISPLAY 1.234043 (-3250 4350);
PAINT GREEN (-3250 4350);
DISPLAY INVISIBLE (-3250 4350);
FORCEPROP 1 LAST HDL_TAP TRUE
J 0
(-2925 4275);
DISPLAY 1.234043 (-2925 4275);
PAINT GREEN (-2925 4275);
DISPLAY INVISIBLE (-2925 4275);
FORCEPROP 1 LAST PATH I122
J 0
(-3250 4400);
DISPLAY 0.936170 (-3250 4400);
PAINT GREEN (-3250 4400);
DISPLAY INVISIBLE (-3250 4400);
FORCEADD TAP..6
(-3250 4350);
FORCEPROP 3 LASTPIN (-3200 4350) SIG_NAME M_L_MA<6>
J 0
(-3190 4360);
DISPLAY 0.659574 (-3190 4360);
PAINT MONO (-3190 4360);
DISPLAY INVISIBLE (-3190 4360);
FORCEPROP 1 LASTPIN (-3200 4350) BN 6
J 0
(-3250 4360);
DISPLAY 0.617021 (-3250 4360);
PAINT PINK (-3250 4360);
FORCEPROP 2 LAST CDS_LIB mstr_standard
J 2
(-3250 4350);
DISPLAY 0.787234 (-3250 4350);
PAINT MONO (-3250 4350);
DISPLAY INVISIBLE (-3250 4350);
FORCEPROP 1 LAST BODY_TYPE PLUMBING
J 0
(-3250 4300);
DISPLAY 1.234043 (-3250 4300);
PAINT GREEN (-3250 4300);
DISPLAY INVISIBLE (-3250 4300);
FORCEPROP 1 LAST HDL_TAP TRUE
J 0
(-2925 4225);
DISPLAY 1.234043 (-2925 4225);
PAINT GREEN (-2925 4225);
DISPLAY INVISIBLE (-2925 4225);
FORCEPROP 1 LAST PATH I123
J 0
(-3250 4350);
DISPLAY 0.936170 (-3250 4350);
PAINT GREEN (-3250 4350);
DISPLAY INVISIBLE (-3250 4350);
FORCEADD TAP..6
(-3250 4300);
FORCEPROP 3 LASTPIN (-3200 4300) SIG_NAME M_L_MA<5>
J 0
(-3190 4310);
DISPLAY 0.659574 (-3190 4310);
PAINT MONO (-3190 4310);
DISPLAY INVISIBLE (-3190 4310);
FORCEPROP 1 LASTPIN (-3200 4300) BN 5
J 0
(-3250 4310);
DISPLAY 0.617021 (-3250 4310);
PAINT PINK (-3250 4310);
FORCEPROP 2 LAST CDS_LIB mstr_standard
J 2
(-3250 4300);
DISPLAY 0.787234 (-3250 4300);
PAINT MONO (-3250 4300);
DISPLAY INVISIBLE (-3250 4300);
FORCEPROP 1 LAST BODY_TYPE PLUMBING
J 0
(-3250 4250);
DISPLAY 1.234043 (-3250 4250);
PAINT GREEN (-3250 4250);
DISPLAY INVISIBLE (-3250 4250);
FORCEPROP 1 LAST HDL_TAP TRUE
J 0
(-2925 4175);
DISPLAY 1.234043 (-2925 4175);
PAINT GREEN (-2925 4175);
DISPLAY INVISIBLE (-2925 4175);
FORCEPROP 1 LAST PATH I124
J 0
(-3250 4300);
DISPLAY 0.936170 (-3250 4300);
PAINT GREEN (-3250 4300);
DISPLAY INVISIBLE (-3250 4300);
FORCEADD TAP..6
(-3250 4250);
FORCEPROP 3 LASTPIN (-3200 4250) SIG_NAME M_L_MA<4>
J 0
(-3190 4260);
DISPLAY 0.659574 (-3190 4260);
PAINT MONO (-3190 4260);
DISPLAY INVISIBLE (-3190 4260);
FORCEPROP 1 LASTPIN (-3200 4250) BN 4
J 0
(-3250 4260);
DISPLAY 0.617021 (-3250 4260);
PAINT PINK (-3250 4260);
FORCEPROP 2 LAST CDS_LIB mstr_standard
J 2
(-3250 4250);
DISPLAY 0.787234 (-3250 4250);
PAINT MONO (-3250 4250);
DISPLAY INVISIBLE (-3250 4250);
FORCEPROP 1 LAST BODY_TYPE PLUMBING
J 0
(-3250 4200);
DISPLAY 1.234043 (-3250 4200);
PAINT GREEN (-3250 4200);
DISPLAY INVISIBLE (-3250 4200);
FORCEPROP 1 LAST HDL_TAP TRUE
J 0
(-2925 4125);
DISPLAY 1.234043 (-2925 4125);
PAINT GREEN (-2925 4125);
DISPLAY INVISIBLE (-2925 4125);
FORCEPROP 1 LAST PATH I125
J 0
(-3250 4250);
DISPLAY 0.936170 (-3250 4250);
PAINT GREEN (-3250 4250);
DISPLAY INVISIBLE (-3250 4250);
FORCEADD TAP..6
(-3250 4150);
FORCEPROP 3 LASTPIN (-3200 4150) SIG_NAME M_L_MA<2>
J 0
(-3190 4160);
DISPLAY 0.659574 (-3190 4160);
PAINT MONO (-3190 4160);
DISPLAY INVISIBLE (-3190 4160);
FORCEPROP 1 LASTPIN (-3200 4150) BN 2
J 0
(-3250 4160);
DISPLAY 0.617021 (-3250 4160);
PAINT PINK (-3250 4160);
FORCEPROP 2 LAST CDS_LIB mstr_standard
J 2
(-3250 4150);
DISPLAY 0.787234 (-3250 4150);
PAINT MONO (-3250 4150);
DISPLAY INVISIBLE (-3250 4150);
FORCEPROP 1 LAST BODY_TYPE PLUMBING
J 0
(-3250 4100);
DISPLAY 1.234043 (-3250 4100);
PAINT GREEN (-3250 4100);
DISPLAY INVISIBLE (-3250 4100);
FORCEPROP 1 LAST HDL_TAP TRUE
J 0
(-2925 4025);
DISPLAY 1.234043 (-2925 4025);
PAINT GREEN (-2925 4025);
DISPLAY INVISIBLE (-2925 4025);
FORCEPROP 1 LAST PATH I126
J 0
(-3250 4150);
DISPLAY 0.936170 (-3250 4150);
PAINT GREEN (-3250 4150);
DISPLAY INVISIBLE (-3250 4150);
FORCEADD TAP..6
(-3250 4200);
FORCEPROP 3 LASTPIN (-3200 4200) SIG_NAME M_L_MA<3>
J 0
(-3190 4210);
DISPLAY 0.659574 (-3190 4210);
PAINT MONO (-3190 4210);
DISPLAY INVISIBLE (-3190 4210);
FORCEPROP 1 LASTPIN (-3200 4200) BN 3
J 0
(-3250 4210);
DISPLAY 0.617021 (-3250 4210);
PAINT PINK (-3250 4210);
FORCEPROP 2 LAST CDS_LIB mstr_standard
J 2
(-3250 4200);
DISPLAY 0.787234 (-3250 4200);
PAINT MONO (-3250 4200);
DISPLAY INVISIBLE (-3250 4200);
FORCEPROP 1 LAST BODY_TYPE PLUMBING
J 0
(-3250 4150);
DISPLAY 1.234043 (-3250 4150);
PAINT GREEN (-3250 4150);
DISPLAY INVISIBLE (-3250 4150);
FORCEPROP 1 LAST HDL_TAP TRUE
J 0
(-2925 4075);
DISPLAY 1.234043 (-2925 4075);
PAINT GREEN (-2925 4075);
DISPLAY INVISIBLE (-2925 4075);
FORCEPROP 1 LAST PATH I127
J 0
(-3250 4200);
DISPLAY 0.936170 (-3250 4200);
PAINT GREEN (-3250 4200);
DISPLAY INVISIBLE (-3250 4200);
FORCEADD TAP..6
(-3250 4100);
FORCEPROP 3 LASTPIN (-3200 4100) SIG_NAME M_L_MA<1>
J 0
(-3190 4110);
DISPLAY 0.659574 (-3190 4110);
PAINT MONO (-3190 4110);
DISPLAY INVISIBLE (-3190 4110);
FORCEPROP 1 LASTPIN (-3200 4100) BN 1
J 0
(-3250 4110);
DISPLAY 0.617021 (-3250 4110);
PAINT PINK (-3250 4110);
FORCEPROP 2 LAST CDS_LIB mstr_standard
J 2
(-3250 4100);
DISPLAY 0.787234 (-3250 4100);
PAINT MONO (-3250 4100);
DISPLAY INVISIBLE (-3250 4100);
FORCEPROP 1 LAST BODY_TYPE PLUMBING
J 0
(-3250 4050);
DISPLAY 1.234043 (-3250 4050);
PAINT GREEN (-3250 4050);
DISPLAY INVISIBLE (-3250 4050);
FORCEPROP 1 LAST HDL_TAP TRUE
J 0
(-2925 3975);
DISPLAY 1.234043 (-2925 3975);
PAINT GREEN (-2925 3975);
DISPLAY INVISIBLE (-2925 3975);
FORCEPROP 1 LAST PATH I128
J 0
(-3250 4100);
DISPLAY 0.936170 (-3250 4100);
PAINT GREEN (-3250 4100);
DISPLAY INVISIBLE (-3250 4100);
FORCEADD TAP..6
(-3250 4050);
FORCEPROP 3 LASTPIN (-3200 4050) SIG_NAME M_L_MA<0>
J 0
(-3190 4060);
DISPLAY 0.659574 (-3190 4060);
PAINT MONO (-3190 4060);
DISPLAY INVISIBLE (-3190 4060);
FORCEPROP 1 LASTPIN (-3200 4050) BN 0
J 0
(-3250 4060);
DISPLAY 0.617021 (-3250 4060);
PAINT PINK (-3250 4060);
FORCEPROP 2 LAST CDS_LIB mstr_standard
J 2
(-3250 4050);
DISPLAY 0.787234 (-3250 4050);
PAINT MONO (-3250 4050);
DISPLAY INVISIBLE (-3250 4050);
FORCEPROP 1 LAST BODY_TYPE PLUMBING
J 0
(-3250 4000);
DISPLAY 1.234043 (-3250 4000);
PAINT GREEN (-3250 4000);
DISPLAY INVISIBLE (-3250 4000);
FORCEPROP 1 LAST HDL_TAP TRUE
J 0
(-2925 3925);
DISPLAY 1.234043 (-2925 3925);
PAINT GREEN (-2925 3925);
DISPLAY INVISIBLE (-2925 3925);
FORCEPROP 1 LAST PATH I129
J 0
(-3250 4050);
DISPLAY 0.936170 (-3250 4050);
PAINT GREEN (-3250 4050);
DISPLAY INVISIBLE (-3250 4050);
FORCEADD TAP..6
R 2
(700 4550);
FORCEPROP 3 LASTPIN (650 4550) SIG_NAME M_L_DQS_DP<11>
J 0
(660 4560);
DISPLAY 0.659574 (660 4560);
PAINT MONO (660 4560);
DISPLAY INVISIBLE (660 4560);
FORCEPROP 1 LASTPIN (650 4550) BN 11
J 2
(700 4560);
DISPLAY 0.617021 (700 4560);
PAINT PINK (700 4560);
FORCEPROP 2 LAST CDS_LIB mstr_standard
J 0
(700 4550);
DISPLAY 0.787234 (700 4550);
PAINT MONO (700 4550);
DISPLAY INVISIBLE (700 4550);
FORCEPROP 1 LAST BODY_TYPE PLUMBING
J 2
(700 4500);
DISPLAY 1.234043 (700 4500);
PAINT GREEN (700 4500);
DISPLAY INVISIBLE (700 4500);
FORCEPROP 1 LAST HDL_TAP TRUE
J 2
(375 4425);
DISPLAY 1.234043 (375 4425);
PAINT GREEN (375 4425);
DISPLAY INVISIBLE (375 4425);
FORCEPROP 1 LAST PATH I13
J 2
(700 4550);
DISPLAY 0.936170 (700 4550);
PAINT GREEN (700 4550);
DISPLAY INVISIBLE (700 4550);
FORCEADD TAP..6
(-3250 3950);
FORCEPROP 3 LASTPIN (-3200 3950) SIG_NAME M_L_BA<1>
J 0
(-3190 3960);
DISPLAY 0.659574 (-3190 3960);
PAINT MONO (-3190 3960);
DISPLAY INVISIBLE (-3190 3960);
FORCEPROP 1 LASTPIN (-3200 3950) BN 1
J 0
(-3250 3960);
DISPLAY 0.617021 (-3250 3960);
PAINT PINK (-3250 3960);
FORCEPROP 2 LAST CDS_LIB mstr_standard
J 0
(-3250 3950);
DISPLAY 0.787234 (-3250 3950);
PAINT MONO (-3250 3950);
DISPLAY INVISIBLE (-3250 3950);
FORCEPROP 1 LAST BODY_TYPE PLUMBING
J 0
(-3250 3900);
DISPLAY 1.234043 (-3250 3900);
PAINT GREEN (-3250 3900);
DISPLAY INVISIBLE (-3250 3900);
FORCEPROP 1 LAST HDL_TAP TRUE
J 0
(-2925 3825);
DISPLAY 1.234043 (-2925 3825);
PAINT GREEN (-2925 3825);
DISPLAY INVISIBLE (-2925 3825);
FORCEPROP 1 LAST PATH I130
J 0
(-3250 3950);
DISPLAY 0.936170 (-3250 3950);
PAINT GREEN (-3250 3950);
DISPLAY INVISIBLE (-3250 3950);
FORCEADD OFFPAGE..1
(-3850 4950);
FORCEPROP 2 LAST $XR0 61 
J 0
(-4101 4950);
DISPLAY 0.638298 (-4101 4950);
PAINT MONO (-4101 4950);
FORCEPROP 2 LAST $XR1 86 
J 0
(-4191 4950);
DISPLAY 0.638298 (-4191 4950);
PAINT MONO (-4191 4950);
FORCEPROP 2 LAST CDS_LIB mstr_standard
J 0
(-3850 4950);
DISPLAY 0.787234 (-3850 4950);
PAINT MONO (-3850 4950);
DISPLAY INVISIBLE (-3850 4950);
FORCEPROP 1 LAST OFFPAGE TRUE
J 0
(-3525 4825);
DISPLAY 0.936170 (-3525 4825);
PAINT GREEN (-3525 4825);
DISPLAY INVISIBLE (-3525 4825);
FORCEPROP 1 LAST COMMENT_BODY TRUE
J 0
(-3725 4850);
DISPLAY 0.936170 (-3725 4850);
PAINT GREEN (-3725 4850);
DISPLAY INVISIBLE (-3725 4850);
FORCEPROP 2 LAST PATH I131
J 0
(-3800 5025);
DISPLAY 0.787234 (-3800 5025);
PAINT MONO (-3800 5025);
DISPLAY INVISIBLE (-3800 5025);
FORCEADD OFFPAGE..1
(-3850 4000);
FORCEPROP 2 LAST $XR0 61 
J 0
(-4101 4000);
DISPLAY 0.638298 (-4101 4000);
PAINT MONO (-4101 4000);
FORCEPROP 2 LAST $XR1 86 
J 0
(-4191 4000);
DISPLAY 0.638298 (-4191 4000);
PAINT MONO (-4191 4000);
FORCEPROP 2 LAST CDS_LIB mstr_standard
J 0
(-3850 4000);
DISPLAY 0.787234 (-3850 4000);
PAINT MONO (-3850 4000);
DISPLAY INVISIBLE (-3850 4000);
FORCEPROP 1 LAST OFFPAGE TRUE
J 0
(-3525 3875);
DISPLAY 0.936170 (-3525 3875);
PAINT GREEN (-3525 3875);
DISPLAY INVISIBLE (-3525 3875);
FORCEPROP 1 LAST COMMENT_BODY TRUE
J 0
(-3725 3900);
DISPLAY 0.936170 (-3725 3900);
PAINT GREEN (-3725 3900);
DISPLAY INVISIBLE (-3725 3900);
FORCEPROP 2 LAST PATH I132
J 0
(-3800 4075);
DISPLAY 0.787234 (-3800 4075);
PAINT MONO (-3800 4075);
DISPLAY INVISIBLE (-3800 4075);
FORCEADD TAP..6
(-3250 3900);
FORCEPROP 3 LASTPIN (-3200 3900) SIG_NAME M_L_BA<0>
J 0
(-3190 3910);
DISPLAY 0.659574 (-3190 3910);
PAINT MONO (-3190 3910);
DISPLAY INVISIBLE (-3190 3910);
FORCEPROP 1 LASTPIN (-3200 3900) BN 0
J 0
(-3250 3910);
DISPLAY 0.617021 (-3250 3910);
PAINT PINK (-3250 3910);
FORCEPROP 2 LAST CDS_LIB mstr_standard
J 0
(-3250 3900);
DISPLAY 0.787234 (-3250 3900);
PAINT MONO (-3250 3900);
DISPLAY INVISIBLE (-3250 3900);
FORCEPROP 1 LAST BODY_TYPE PLUMBING
J 0
(-3250 3850);
DISPLAY 1.234043 (-3250 3850);
PAINT GREEN (-3250 3850);
DISPLAY INVISIBLE (-3250 3850);
FORCEPROP 1 LAST HDL_TAP TRUE
J 0
(-2925 3775);
DISPLAY 1.234043 (-2925 3775);
PAINT GREEN (-2925 3775);
DISPLAY INVISIBLE (-2925 3775);
FORCEPROP 1 LAST PATH I133
J 0
(-3250 3900);
DISPLAY 0.936170 (-3250 3900);
PAINT GREEN (-3250 3900);
DISPLAY INVISIBLE (-3250 3900);
FORCEADD TAP..6
(-3250 3850);
FORCEPROP 3 LASTPIN (-3200 3850) SIG_NAME M_L_BG<1>
J 0
(-3190 3860);
DISPLAY 0.659574 (-3190 3860);
PAINT MONO (-3190 3860);
DISPLAY INVISIBLE (-3190 3860);
FORCEPROP 1 LASTPIN (-3200 3850) BN 1
J 0
(-3250 3860);
DISPLAY 0.617021 (-3250 3860);
PAINT PINK (-3250 3860);
FORCEPROP 2 LAST CDS_LIB mstr_standard
J 0
(-3250 3850);
DISPLAY 0.787234 (-3250 3850);
PAINT MONO (-3250 3850);
DISPLAY INVISIBLE (-3250 3850);
FORCEPROP 1 LAST BODY_TYPE PLUMBING
J 0
(-3250 3800);
DISPLAY 1.234043 (-3250 3800);
PAINT GREEN (-3250 3800);
DISPLAY INVISIBLE (-3250 3800);
FORCEPROP 1 LAST HDL_TAP TRUE
J 0
(-2925 3725);
DISPLAY 1.234043 (-2925 3725);
PAINT GREEN (-2925 3725);
DISPLAY INVISIBLE (-2925 3725);
FORCEPROP 1 LAST PATH I134
J 0
(-3250 3850);
DISPLAY 0.936170 (-3250 3850);
PAINT GREEN (-3250 3850);
DISPLAY INVISIBLE (-3250 3850);
FORCEADD TAP..6
(-3250 3800);
FORCEPROP 3 LASTPIN (-3200 3800) SIG_NAME M_L_BG<0>
J 0
(-3190 3810);
DISPLAY 0.659574 (-3190 3810);
PAINT MONO (-3190 3810);
DISPLAY INVISIBLE (-3190 3810);
FORCEPROP 1 LASTPIN (-3200 3800) BN 0
J 0
(-3250 3810);
DISPLAY 0.617021 (-3250 3810);
PAINT PINK (-3250 3810);
FORCEPROP 2 LAST CDS_LIB mstr_standard
J 0
(-3250 3800);
DISPLAY 0.787234 (-3250 3800);
PAINT MONO (-3250 3800);
DISPLAY INVISIBLE (-3250 3800);
FORCEPROP 1 LAST BODY_TYPE PLUMBING
J 0
(-3250 3750);
DISPLAY 1.234043 (-3250 3750);
PAINT GREEN (-3250 3750);
DISPLAY INVISIBLE (-3250 3750);
FORCEPROP 1 LAST HDL_TAP TRUE
J 0
(-2925 3675);
DISPLAY 1.234043 (-2925 3675);
PAINT GREEN (-2925 3675);
DISPLAY INVISIBLE (-2925 3675);
FORCEPROP 1 LAST PATH I135
J 0
(-3250 3800);
DISPLAY 0.936170 (-3250 3800);
PAINT GREEN (-3250 3800);
DISPLAY INVISIBLE (-3250 3800);
FORCEADD OFFPAGE..1
(-3850 3500);
FORCEPROP 2 LAST $XR0 61 
J 0
(-4101 3500);
DISPLAY 0.638298 (-4101 3500);
PAINT MONO (-4101 3500);
FORCEPROP 2 LAST $XR1 86 
J 0
(-4191 3500);
DISPLAY 0.638298 (-4191 3500);
PAINT MONO (-4191 3500);
FORCEPROP 2 LAST CDS_LIB mstr_standard
J 0
(-3850 3500);
DISPLAY 0.787234 (-3850 3500);
PAINT MONO (-3850 3500);
DISPLAY INVISIBLE (-3850 3500);
FORCEPROP 1 LAST OFFPAGE TRUE
J 0
(-3525 3375);
DISPLAY 0.936170 (-3525 3375);
PAINT GREEN (-3525 3375);
DISPLAY INVISIBLE (-3525 3375);
FORCEPROP 1 LAST COMMENT_BODY TRUE
J 0
(-3725 3400);
DISPLAY 0.936170 (-3725 3400);
PAINT GREEN (-3725 3400);
DISPLAY INVISIBLE (-3725 3400);
FORCEPROP 2 LAST PATH I136
J 0
(-3800 3575);
DISPLAY 0.787234 (-3800 3575);
PAINT MONO (-3800 3575);
DISPLAY INVISIBLE (-3800 3575);
FORCEADD OFFPAGE..1
(-3850 3875);
FORCEPROP 2 LAST $XR0 61 
J 0
(-4101 3875);
DISPLAY 0.638298 (-4101 3875);
PAINT MONO (-4101 3875);
FORCEPROP 2 LAST $XR1 86 
J 0
(-4191 3875);
DISPLAY 0.638298 (-4191 3875);
PAINT MONO (-4191 3875);
FORCEPROP 2 LAST CDS_LIB mstr_standard
J 0
(-3850 3875);
DISPLAY 0.787234 (-3850 3875);
PAINT MONO (-3850 3875);
DISPLAY INVISIBLE (-3850 3875);
FORCEPROP 1 LAST OFFPAGE TRUE
J 0
(-3525 3750);
DISPLAY 0.936170 (-3525 3750);
PAINT GREEN (-3525 3750);
DISPLAY INVISIBLE (-3525 3750);
FORCEPROP 1 LAST COMMENT_BODY TRUE
J 0
(-3725 3775);
DISPLAY 0.936170 (-3725 3775);
PAINT GREEN (-3725 3775);
DISPLAY INVISIBLE (-3725 3775);
FORCEPROP 2 LAST PATH I137
J 0
(-3800 3950);
DISPLAY 0.787234 (-3800 3950);
PAINT MONO (-3800 3950);
DISPLAY INVISIBLE (-3800 3950);
FORCEADD TAP..6
(-3250 2850);
FORCEPROP 3 LASTPIN (-3200 2850) SIG_NAME M_L_ECC<6>
J 0
(-3190 2860);
DISPLAY 0.659574 (-3190 2860);
PAINT MONO (-3190 2860);
DISPLAY INVISIBLE (-3190 2860);
FORCEPROP 1 LASTPIN (-3200 2850) BN 6
J 0
(-3250 2860);
DISPLAY 0.617021 (-3250 2860);
PAINT PINK (-3250 2860);
FORCEPROP 2 LAST CDS_LIB mstr_standard
J 0
(-3250 2850);
DISPLAY 0.787234 (-3250 2850);
PAINT MONO (-3250 2850);
DISPLAY INVISIBLE (-3250 2850);
FORCEPROP 1 LAST BODY_TYPE PLUMBING
J 0
(-3250 2800);
DISPLAY 1.234043 (-3250 2800);
PAINT GREEN (-3250 2800);
DISPLAY INVISIBLE (-3250 2800);
FORCEPROP 1 LAST HDL_TAP TRUE
J 0
(-2925 2725);
DISPLAY 1.234043 (-2925 2725);
PAINT GREEN (-2925 2725);
DISPLAY INVISIBLE (-2925 2725);
FORCEPROP 1 LAST PATH I138
J 0
(-3250 2850);
DISPLAY 0.936170 (-3250 2850);
PAINT GREEN (-3250 2850);
DISPLAY INVISIBLE (-3250 2850);
FORCEADD TAP..6
(-3250 2800);
FORCEPROP 3 LASTPIN (-3200 2800) SIG_NAME M_L_ECC<7>
J 0
(-3190 2810);
DISPLAY 0.659574 (-3190 2810);
PAINT MONO (-3190 2810);
DISPLAY INVISIBLE (-3190 2810);
FORCEPROP 1 LASTPIN (-3200 2800) BN 7
J 0
(-3250 2810);
DISPLAY 0.617021 (-3250 2810);
PAINT PINK (-3250 2810);
FORCEPROP 2 LAST CDS_LIB mstr_standard
J 0
(-3250 2800);
DISPLAY 0.787234 (-3250 2800);
PAINT MONO (-3250 2800);
DISPLAY INVISIBLE (-3250 2800);
FORCEPROP 1 LAST BODY_TYPE PLUMBING
J 0
(-3250 2750);
DISPLAY 1.234043 (-3250 2750);
PAINT GREEN (-3250 2750);
DISPLAY INVISIBLE (-3250 2750);
FORCEPROP 1 LAST HDL_TAP TRUE
J 0
(-2925 2675);
DISPLAY 1.234043 (-2925 2675);
PAINT GREEN (-2925 2675);
DISPLAY INVISIBLE (-2925 2675);
FORCEPROP 1 LAST PATH I139
J 0
(-3250 2800);
DISPLAY 0.936170 (-3250 2800);
PAINT GREEN (-3250 2800);
DISPLAY INVISIBLE (-3250 2800);
FORCEADD TAP..6
R 2
(700 4650);
FORCEPROP 3 LASTPIN (650 4650) SIG_NAME M_L_DQS_DP<12>
J 0
(660 4660);
DISPLAY 0.659574 (660 4660);
PAINT MONO (660 4660);
DISPLAY INVISIBLE (660 4660);
FORCEPROP 1 LASTPIN (650 4650) BN 12
J 2
(700 4660);
DISPLAY 0.617021 (700 4660);
PAINT PINK (700 4660);
FORCEPROP 2 LAST CDS_LIB mstr_standard
J 0
(700 4650);
DISPLAY 0.787234 (700 4650);
PAINT MONO (700 4650);
DISPLAY INVISIBLE (700 4650);
FORCEPROP 1 LAST BODY_TYPE PLUMBING
J 2
(700 4600);
DISPLAY 1.234043 (700 4600);
PAINT GREEN (700 4600);
DISPLAY INVISIBLE (700 4600);
FORCEPROP 1 LAST HDL_TAP TRUE
J 2
(375 4525);
DISPLAY 1.234043 (375 4525);
PAINT GREEN (375 4525);
DISPLAY INVISIBLE (375 4525);
FORCEPROP 1 LAST PATH I14
J 2
(700 4650);
DISPLAY 0.936170 (700 4650);
PAINT GREEN (700 4650);
DISPLAY INVISIBLE (700 4650);
FORCEADD TAP..6
(-3250 2750);
FORCEPROP 3 LASTPIN (-3200 2750) SIG_NAME M_L_ECC<4>
J 0
(-3190 2760);
DISPLAY 0.659574 (-3190 2760);
PAINT MONO (-3190 2760);
DISPLAY INVISIBLE (-3190 2760);
FORCEPROP 1 LASTPIN (-3200 2750) BN 4
J 0
(-3250 2760);
DISPLAY 0.617021 (-3250 2760);
PAINT PINK (-3250 2760);
FORCEPROP 2 LAST CDS_LIB mstr_standard
J 0
(-3250 2750);
DISPLAY 0.787234 (-3250 2750);
PAINT MONO (-3250 2750);
DISPLAY INVISIBLE (-3250 2750);
FORCEPROP 1 LAST BODY_TYPE PLUMBING
J 0
(-3250 2700);
DISPLAY 1.234043 (-3250 2700);
PAINT GREEN (-3250 2700);
DISPLAY INVISIBLE (-3250 2700);
FORCEPROP 1 LAST HDL_TAP TRUE
J 0
(-2925 2625);
DISPLAY 1.234043 (-2925 2625);
PAINT GREEN (-2925 2625);
DISPLAY INVISIBLE (-2925 2625);
FORCEPROP 1 LAST PATH I140
J 0
(-3250 2750);
DISPLAY 0.936170 (-3250 2750);
PAINT GREEN (-3250 2750);
DISPLAY INVISIBLE (-3250 2750);
FORCEADD TAP..6
(-3250 2700);
FORCEPROP 3 LASTPIN (-3200 2700) SIG_NAME M_L_ECC<5>
J 0
(-3190 2710);
DISPLAY 0.659574 (-3190 2710);
PAINT MONO (-3190 2710);
DISPLAY INVISIBLE (-3190 2710);
FORCEPROP 1 LASTPIN (-3200 2700) BN 5
J 0
(-3250 2710);
DISPLAY 0.617021 (-3250 2710);
PAINT PINK (-3250 2710);
FORCEPROP 2 LAST CDS_LIB mstr_standard
J 0
(-3250 2700);
DISPLAY 0.787234 (-3250 2700);
PAINT MONO (-3250 2700);
DISPLAY INVISIBLE (-3250 2700);
FORCEPROP 1 LAST BODY_TYPE PLUMBING
J 0
(-3250 2650);
DISPLAY 1.234043 (-3250 2650);
PAINT GREEN (-3250 2650);
DISPLAY INVISIBLE (-3250 2650);
FORCEPROP 1 LAST HDL_TAP TRUE
J 0
(-2925 2575);
DISPLAY 1.234043 (-2925 2575);
PAINT GREEN (-2925 2575);
DISPLAY INVISIBLE (-2925 2575);
FORCEPROP 1 LAST PATH I141
J 0
(-3250 2700);
DISPLAY 0.936170 (-3250 2700);
PAINT GREEN (-3250 2700);
DISPLAY INVISIBLE (-3250 2700);
FORCEADD TAP..6
(-3250 2650);
FORCEPROP 3 LASTPIN (-3200 2650) SIG_NAME M_L_ECC<2>
J 0
(-3190 2660);
DISPLAY 0.659574 (-3190 2660);
PAINT MONO (-3190 2660);
DISPLAY INVISIBLE (-3190 2660);
FORCEPROP 1 LASTPIN (-3200 2650) BN 2
J 0
(-3250 2660);
DISPLAY 0.617021 (-3250 2660);
PAINT PINK (-3250 2660);
FORCEPROP 2 LAST CDS_LIB mstr_standard
J 0
(-3250 2650);
DISPLAY 0.787234 (-3250 2650);
PAINT MONO (-3250 2650);
DISPLAY INVISIBLE (-3250 2650);
FORCEPROP 1 LAST BODY_TYPE PLUMBING
J 0
(-3250 2600);
DISPLAY 1.234043 (-3250 2600);
PAINT GREEN (-3250 2600);
DISPLAY INVISIBLE (-3250 2600);
FORCEPROP 1 LAST HDL_TAP TRUE
J 0
(-2925 2525);
DISPLAY 1.234043 (-2925 2525);
PAINT GREEN (-2925 2525);
DISPLAY INVISIBLE (-2925 2525);
FORCEPROP 1 LAST PATH I142
J 0
(-3250 2650);
DISPLAY 0.936170 (-3250 2650);
PAINT GREEN (-3250 2650);
DISPLAY INVISIBLE (-3250 2650);
FORCEADD TAP..6
(-3250 2600);
FORCEPROP 3 LASTPIN (-3200 2600) SIG_NAME M_L_ECC<3>
J 0
(-3190 2610);
DISPLAY 0.659574 (-3190 2610);
PAINT MONO (-3190 2610);
DISPLAY INVISIBLE (-3190 2610);
FORCEPROP 1 LASTPIN (-3200 2600) BN 3
J 0
(-3250 2610);
DISPLAY 0.617021 (-3250 2610);
PAINT PINK (-3250 2610);
FORCEPROP 2 LAST CDS_LIB mstr_standard
J 0
(-3250 2600);
DISPLAY 0.787234 (-3250 2600);
PAINT MONO (-3250 2600);
DISPLAY INVISIBLE (-3250 2600);
FORCEPROP 1 LAST BODY_TYPE PLUMBING
J 0
(-3250 2550);
DISPLAY 1.234043 (-3250 2550);
PAINT GREEN (-3250 2550);
DISPLAY INVISIBLE (-3250 2550);
FORCEPROP 1 LAST HDL_TAP TRUE
J 0
(-2925 2475);
DISPLAY 1.234043 (-2925 2475);
PAINT GREEN (-2925 2475);
DISPLAY INVISIBLE (-2925 2475);
FORCEPROP 1 LAST PATH I143
J 0
(-3250 2600);
DISPLAY 0.936170 (-3250 2600);
PAINT GREEN (-3250 2600);
DISPLAY INVISIBLE (-3250 2600);
FORCEADD TAP..6
(-3250 2550);
FORCEPROP 3 LASTPIN (-3200 2550) SIG_NAME M_L_ECC<0>
J 0
(-3190 2560);
DISPLAY 0.659574 (-3190 2560);
PAINT MONO (-3190 2560);
DISPLAY INVISIBLE (-3190 2560);
FORCEPROP 1 LASTPIN (-3200 2550) BN 0
J 0
(-3250 2560);
DISPLAY 0.617021 (-3250 2560);
PAINT PINK (-3250 2560);
FORCEPROP 2 LAST CDS_LIB mstr_standard
J 0
(-3250 2550);
DISPLAY 0.787234 (-3250 2550);
PAINT MONO (-3250 2550);
DISPLAY INVISIBLE (-3250 2550);
FORCEPROP 1 LAST BODY_TYPE PLUMBING
J 0
(-3250 2500);
DISPLAY 1.234043 (-3250 2500);
PAINT GREEN (-3250 2500);
DISPLAY INVISIBLE (-3250 2500);
FORCEPROP 1 LAST HDL_TAP TRUE
J 0
(-2925 2425);
DISPLAY 1.234043 (-2925 2425);
PAINT GREEN (-2925 2425);
DISPLAY INVISIBLE (-2925 2425);
FORCEPROP 1 LAST PATH I144
J 0
(-3250 2550);
DISPLAY 0.936170 (-3250 2550);
PAINT GREEN (-3250 2550);
DISPLAY INVISIBLE (-3250 2550);
FORCEADD TAP..6
(-3250 2500);
FORCEPROP 3 LASTPIN (-3200 2500) SIG_NAME M_L_ECC<1>
J 0
(-3190 2510);
DISPLAY 0.659574 (-3190 2510);
PAINT MONO (-3190 2510);
DISPLAY INVISIBLE (-3190 2510);
FORCEPROP 1 LASTPIN (-3200 2500) BN 1
J 0
(-3250 2510);
DISPLAY 0.617021 (-3250 2510);
PAINT PINK (-3250 2510);
FORCEPROP 2 LAST CDS_LIB mstr_standard
J 0
(-3250 2500);
DISPLAY 0.787234 (-3250 2500);
PAINT MONO (-3250 2500);
DISPLAY INVISIBLE (-3250 2500);
FORCEPROP 1 LAST BODY_TYPE PLUMBING
J 0
(-3250 2450);
DISPLAY 1.234043 (-3250 2450);
PAINT GREEN (-3250 2450);
DISPLAY INVISIBLE (-3250 2450);
FORCEPROP 1 LAST HDL_TAP TRUE
J 0
(-2925 2375);
DISPLAY 1.234043 (-2925 2375);
PAINT GREEN (-2925 2375);
DISPLAY INVISIBLE (-2925 2375);
FORCEPROP 1 LAST PATH I145
J 0
(-3250 2500);
DISPLAY 0.936170 (-3250 2500);
PAINT GREEN (-3250 2500);
DISPLAY INVISIBLE (-3250 2500);
FORCEADD OFFPAGE..1
(-3850 2850);
FORCEPROP 2 LAST $XR0 61 
J 0
(-4101 2850);
DISPLAY 0.638298 (-4101 2850);
PAINT MONO (-4101 2850);
FORCEPROP 2 LAST $XR1 86 
J 0
(-4191 2850);
DISPLAY 0.638298 (-4191 2850);
PAINT MONO (-4191 2850);
FORCEPROP 2 LAST CDS_LIB mstr_standard
J 0
(-3850 2850);
DISPLAY 0.787234 (-3850 2850);
PAINT MONO (-3850 2850);
DISPLAY INVISIBLE (-3850 2850);
FORCEPROP 1 LAST OFFPAGE TRUE
J 0
(-3525 2725);
DISPLAY 0.936170 (-3525 2725);
PAINT GREEN (-3525 2725);
DISPLAY INVISIBLE (-3525 2725);
FORCEPROP 1 LAST COMMENT_BODY TRUE
J 0
(-3725 2750);
DISPLAY 0.936170 (-3725 2750);
PAINT GREEN (-3725 2750);
DISPLAY INVISIBLE (-3725 2750);
FORCEPROP 2 LAST PATH I146
J 0
(-3800 2925);
DISPLAY 0.787234 (-3800 2925);
PAINT MONO (-3800 2925);
DISPLAY INVISIBLE (-3800 2925);
FORCEADD OFFPAGE..1
(-4050 2200);
FORCEPROP 2 LAST $XR0 61 
J 0
(-4301 2200);
DISPLAY 0.638298 (-4301 2200);
PAINT MONO (-4301 2200);
FORCEPROP 2 LAST $XR1 86 
J 0
(-4391 2200);
DISPLAY 0.638298 (-4391 2200);
PAINT MONO (-4391 2200);
FORCEPROP 2 LAST CDS_LIB mstr_standard
J 0
(-4050 2200);
DISPLAY 0.787234 (-4050 2200);
PAINT MONO (-4050 2200);
DISPLAY INVISIBLE (-4050 2200);
FORCEPROP 1 LAST OFFPAGE TRUE
J 0
(-3725 2075);
DISPLAY 0.936170 (-3725 2075);
PAINT GREEN (-3725 2075);
DISPLAY INVISIBLE (-3725 2075);
FORCEPROP 1 LAST COMMENT_BODY TRUE
J 0
(-3925 2100);
DISPLAY 0.936170 (-3925 2100);
PAINT GREEN (-3925 2100);
DISPLAY INVISIBLE (-3925 2100);
FORCEPROP 2 LAST PATH I147
J 0
(-4000 2275);
DISPLAY 0.787234 (-4000 2275);
PAINT MONO (-4000 2275);
DISPLAY INVISIBLE (-4000 2275);
FORCEADD OFFPAGE..5
(-4075 2250);
FORCEPROP 2 LAST $XR0 86 
J 0
(-4299 2250);
DISPLAY 0.638298 (-4299 2250);
PAINT MONO (-4299 2250);
FORCEPROP 2 LAST $XR1 61 
J 0
(-4389 2250);
DISPLAY 0.638298 (-4389 2250);
PAINT MONO (-4389 2250);
FORCEPROP 2 LAST CDS_LIB mstr_standard
J 0
(-4075 2250);
DISPLAY 0.787234 (-4075 2250);
PAINT MONO (-4075 2250);
DISPLAY INVISIBLE (-4075 2250);
FORCEPROP 1 LAST OFFPAGE TRUE
J 0
(-3750 2125);
DISPLAY 1.404255 (-3750 2125);
PAINT GREEN (-3750 2125);
DISPLAY INVISIBLE (-3750 2125);
FORCEPROP 1 LAST COMMENT_BODY TRUE
J 0
(-3975 2175);
DISPLAY 1.404255 (-3975 2175);
PAINT GREEN (-3975 2175);
DISPLAY INVISIBLE (-3975 2175);
FORCEPROP 2 LAST PATH I148
J 0
(-4025 2325);
DISPLAY 0.787234 (-4025 2325);
PAINT MONO (-4025 2325);
DISPLAY INVISIBLE (-4025 2325);
FORCEADD OFFPAGE..1
(-3850 2800);
FORCEPROP 2 LAST $XR0 55 
J 0
(-4101 2800);
DISPLAY 0.638298 (-4101 2800);
PAINT MONO (-4101 2800);
FORCEPROP 2 LAST $XR1 83 
J 0
(-4191 2800);
DISPLAY 0.638298 (-4191 2800);
PAINT MONO (-4191 2800);
FORCEPROP 2 LAST $XR2 84 
J 0
(-4281 2800);
DISPLAY 0.638298 (-4281 2800);
PAINT MONO (-4281 2800);
FORCEPROP 2 LAST $XR3 86 
J 0
(-4371 2800);
DISPLAY 0.638298 (-4371 2800);
PAINT MONO (-4371 2800);
FORCEPROP 2 LAST $XR4 87 
J 0
(-4461 2800);
DISPLAY 0.638298 (-4461 2800);
PAINT MONO (-4461 2800);
FORCEPROP 2 LAST $XR5 88 
J 0
(-4551 2800);
DISPLAY 0.638298 (-4551 2800);
PAINT MONO (-4551 2800);
FORCEPROP 2 LAST CDS_LIB mstr_standard
J 0
(-3850 2800);
DISPLAY 0.787234 (-3850 2800);
PAINT MONO (-3850 2800);
DISPLAY INVISIBLE (-3850 2800);
FORCEPROP 1 LAST OFFPAGE TRUE
J 0
(-3525 2675);
DISPLAY 0.936170 (-3525 2675);
PAINT GREEN (-3525 2675);
DISPLAY INVISIBLE (-3525 2675);
FORCEPROP 1 LAST COMMENT_BODY TRUE
J 0
(-3725 2700);
DISPLAY 0.936170 (-3725 2700);
PAINT GREEN (-3725 2700);
DISPLAY INVISIBLE (-3725 2700);
FORCEPROP 2 LAST PATH I149
J 0
(-3800 2875);
DISPLAY 0.787234 (-3800 2875);
PAINT MONO (-3800 2875);
DISPLAY INVISIBLE (-3800 2875);
FORCEADD TAP..6
R 2
(700 4750);
FORCEPROP 3 LASTPIN (650 4750) SIG_NAME M_L_DQS_DP<13>
J 0
(660 4760);
DISPLAY 0.659574 (660 4760);
PAINT MONO (660 4760);
DISPLAY INVISIBLE (660 4760);
FORCEPROP 1 LASTPIN (650 4750) BN 13
J 2
(700 4760);
DISPLAY 0.617021 (700 4760);
PAINT PINK (700 4760);
FORCEPROP 2 LAST CDS_LIB mstr_standard
J 0
(700 4750);
DISPLAY 0.787234 (700 4750);
PAINT MONO (700 4750);
DISPLAY INVISIBLE (700 4750);
FORCEPROP 1 LAST BODY_TYPE PLUMBING
J 2
(700 4700);
DISPLAY 1.234043 (700 4700);
PAINT GREEN (700 4700);
DISPLAY INVISIBLE (700 4700);
FORCEPROP 1 LAST HDL_TAP TRUE
J 2
(375 4625);
DISPLAY 1.234043 (375 4625);
PAINT GREEN (375 4625);
DISPLAY INVISIBLE (375 4625);
FORCEPROP 1 LAST PATH I15
J 2
(700 4750);
DISPLAY 0.936170 (700 4750);
PAINT GREEN (700 4750);
DISPLAY INVISIBLE (700 4750);
FORCEADD OFFPAGE..6
(-3850 2900);
FORCEPROP 2 LAST $XR0 61 
J 0
(-4099 2900);
DISPLAY 0.638298 (-4099 2900);
PAINT MONO (-4099 2900);
FORCEPROP 2 LAST $XR1 86 
J 0
(-4189 2900);
DISPLAY 0.638298 (-4189 2900);
PAINT MONO (-4189 2900);
FORCEPROP 2 LAST CDS_LIB mstr_standard
J 0
(-3850 2900);
DISPLAY 0.787234 (-3850 2900);
PAINT MONO (-3850 2900);
DISPLAY INVISIBLE (-3850 2900);
FORCEPROP 1 LAST OFFPAGE TRUE
J 0
(-3525 2775);
DISPLAY 0.936170 (-3525 2775);
PAINT GREEN (-3525 2775);
DISPLAY INVISIBLE (-3525 2775);
FORCEPROP 1 LAST COMMENT_BODY TRUE
J 0
(-3750 2825);
DISPLAY 0.936170 (-3750 2825);
PAINT GREEN (-3750 2825);
DISPLAY INVISIBLE (-3750 2825);
FORCEPROP 2 LAST PATH I150
J 0
(-3800 2975);
DISPLAY 0.787234 (-3800 2975);
PAINT MONO (-3800 2975);
DISPLAY INVISIBLE (-3800 2975);
FORCEADD TAP..6
(-3250 3700);
FORCEPROP 3 LASTPIN (-3200 3700) SIG_NAME M_L_CLK_DP<1>
J 0
(-3190 3710);
DISPLAY 0.659574 (-3190 3710);
PAINT MONO (-3190 3710);
DISPLAY INVISIBLE (-3190 3710);
FORCEPROP 1 LASTPIN (-3200 3700) BN 1
J 0
(-3250 3710);
DISPLAY 0.617021 (-3250 3710);
PAINT PINK (-3250 3710);
FORCEPROP 2 LAST CDS_LIB mstr_standard
J 0
(-3250 3700);
DISPLAY 0.787234 (-3250 3700);
PAINT MONO (-3250 3700);
DISPLAY INVISIBLE (-3250 3700);
FORCEPROP 1 LAST BODY_TYPE PLUMBING
J 0
(-3250 3650);
DISPLAY 1.234043 (-3250 3650);
PAINT GREEN (-3250 3650);
DISPLAY INVISIBLE (-3250 3650);
FORCEPROP 1 LAST HDL_TAP TRUE
J 0
(-2925 3575);
DISPLAY 1.234043 (-2925 3575);
PAINT GREEN (-2925 3575);
DISPLAY INVISIBLE (-2925 3575);
FORCEPROP 1 LAST PATH I152
J 0
(-3250 3700);
DISPLAY 0.936170 (-3250 3700);
PAINT GREEN (-3250 3700);
DISPLAY INVISIBLE (-3250 3700);
FORCEADD TAP..6
(-3250 3600);
FORCEPROP 3 LASTPIN (-3200 3600) SIG_NAME M_L_CLK_DP<0>
J 0
(-3190 3610);
DISPLAY 0.659574 (-3190 3610);
PAINT MONO (-3190 3610);
DISPLAY INVISIBLE (-3190 3610);
FORCEPROP 1 LASTPIN (-3200 3600) BN 0
J 0
(-3250 3610);
DISPLAY 0.617021 (-3250 3610);
PAINT PINK (-3250 3610);
FORCEPROP 2 LAST CDS_LIB mstr_standard
J 0
(-3250 3600);
DISPLAY 0.787234 (-3250 3600);
PAINT MONO (-3250 3600);
DISPLAY INVISIBLE (-3250 3600);
FORCEPROP 1 LAST BODY_TYPE PLUMBING
J 0
(-3250 3550);
DISPLAY 1.234043 (-3250 3550);
PAINT GREEN (-3250 3550);
DISPLAY INVISIBLE (-3250 3550);
FORCEPROP 1 LAST HDL_TAP TRUE
J 0
(-2925 3475);
DISPLAY 1.234043 (-2925 3475);
PAINT GREEN (-2925 3475);
DISPLAY INVISIBLE (-2925 3475);
FORCEPROP 1 LAST PATH I153
J 0
(-3250 3600);
DISPLAY 0.936170 (-3250 3600);
PAINT GREEN (-3250 3600);
DISPLAY INVISIBLE (-3250 3600);
FORCEADD TAP..6
(-3450 3650);
FORCEPROP 3 LASTPIN (-3400 3650) SIG_NAME M_L_CLK_DN<1>
J 0
(-3390 3660);
DISPLAY 0.659574 (-3390 3660);
PAINT MONO (-3390 3660);
DISPLAY INVISIBLE (-3390 3660);
FORCEPROP 1 LASTPIN (-3400 3650) BN 1
J 0
(-3450 3660);
DISPLAY 0.617021 (-3450 3660);
PAINT PINK (-3450 3660);
FORCEPROP 2 LAST CDS_LIB mstr_standard
J 0
(-3450 3650);
DISPLAY 0.787234 (-3450 3650);
PAINT MONO (-3450 3650);
DISPLAY INVISIBLE (-3450 3650);
FORCEPROP 1 LAST BODY_TYPE PLUMBING
J 0
(-3450 3600);
DISPLAY 1.234043 (-3450 3600);
PAINT GREEN (-3450 3600);
DISPLAY INVISIBLE (-3450 3600);
FORCEPROP 1 LAST HDL_TAP TRUE
J 0
(-3125 3525);
DISPLAY 1.234043 (-3125 3525);
PAINT GREEN (-3125 3525);
DISPLAY INVISIBLE (-3125 3525);
FORCEPROP 1 LAST PATH I154
J 0
(-3450 3650);
DISPLAY 0.936170 (-3450 3650);
PAINT GREEN (-3450 3650);
DISPLAY INVISIBLE (-3450 3650);
FORCEADD TAP..6
(-3450 3550);
FORCEPROP 3 LASTPIN (-3400 3550) SIG_NAME M_L_CLK_DN<0>
J 0
(-3390 3560);
DISPLAY 0.659574 (-3390 3560);
PAINT MONO (-3390 3560);
DISPLAY INVISIBLE (-3390 3560);
FORCEPROP 1 LASTPIN (-3400 3550) BN 0
J 0
(-3450 3560);
DISPLAY 0.617021 (-3450 3560);
PAINT PINK (-3450 3560);
FORCEPROP 2 LAST CDS_LIB mstr_standard
J 0
(-3450 3550);
DISPLAY 0.787234 (-3450 3550);
PAINT MONO (-3450 3550);
DISPLAY INVISIBLE (-3450 3550);
FORCEPROP 1 LAST BODY_TYPE PLUMBING
J 0
(-3450 3500);
DISPLAY 1.234043 (-3450 3500);
PAINT GREEN (-3450 3500);
DISPLAY INVISIBLE (-3450 3500);
FORCEPROP 1 LAST HDL_TAP TRUE
J 0
(-3125 3425);
DISPLAY 1.234043 (-3125 3425);
PAINT GREEN (-3125 3425);
DISPLAY INVISIBLE (-3125 3425);
FORCEPROP 1 LAST PATH I155
J 0
(-3450 3550);
DISPLAY 0.936170 (-3450 3550);
PAINT GREEN (-3450 3550);
DISPLAY INVISIBLE (-3450 3550);
FORCEADD OFFPAGE..1
(-3850 3750);
FORCEPROP 2 LAST $XR0 61 
J 0
(-4101 3750);
DISPLAY 0.638298 (-4101 3750);
PAINT MONO (-4101 3750);
FORCEPROP 2 LAST $XR1 86 
J 0
(-4191 3750);
DISPLAY 0.638298 (-4191 3750);
PAINT MONO (-4191 3750);
FORCEPROP 2 LAST CDS_LIB mstr_standard
J 0
(-3850 3750);
DISPLAY 0.787234 (-3850 3750);
PAINT MONO (-3850 3750);
DISPLAY INVISIBLE (-3850 3750);
FORCEPROP 1 LAST OFFPAGE TRUE
J 0
(-3525 3625);
DISPLAY 0.936170 (-3525 3625);
PAINT GREEN (-3525 3625);
DISPLAY INVISIBLE (-3525 3625);
FORCEPROP 1 LAST COMMENT_BODY TRUE
J 0
(-3725 3650);
DISPLAY 0.936170 (-3725 3650);
PAINT GREEN (-3725 3650);
DISPLAY INVISIBLE (-3725 3650);
FORCEPROP 2 LAST PATH I156
J 0
(-3800 3825);
DISPLAY 0.787234 (-3800 3825);
PAINT MONO (-3800 3825);
DISPLAY INVISIBLE (-3800 3825);
FORCEADD OFFPAGE..1
(-3850 3700);
FORCEPROP 2 LAST $XR0 61 
J 0
(-4101 3700);
DISPLAY 0.638298 (-4101 3700);
PAINT MONO (-4101 3700);
FORCEPROP 2 LAST $XR1 86 
J 0
(-4191 3700);
DISPLAY 0.638298 (-4191 3700);
PAINT MONO (-4191 3700);
FORCEPROP 2 LAST CDS_LIB mstr_standard
J 0
(-3850 3700);
DISPLAY 0.787234 (-3850 3700);
PAINT MONO (-3850 3700);
DISPLAY INVISIBLE (-3850 3700);
FORCEPROP 1 LAST OFFPAGE TRUE
J 0
(-3525 3575);
DISPLAY 0.936170 (-3525 3575);
PAINT GREEN (-3525 3575);
DISPLAY INVISIBLE (-3525 3575);
FORCEPROP 1 LAST COMMENT_BODY TRUE
J 0
(-3725 3600);
DISPLAY 0.936170 (-3725 3600);
PAINT GREEN (-3725 3600);
DISPLAY INVISIBLE (-3725 3600);
FORCEPROP 2 LAST PATH I157
J 0
(-3800 3775);
DISPLAY 0.787234 (-3800 3775);
PAINT MONO (-3800 3775);
DISPLAY INVISIBLE (-3800 3775);
FORCEADD TAP..6
(-3250 3400);
FORCEPROP 3 LASTPIN (-3200 3400) SIG_NAME M_L_CS_N<3>
J 0
(-3190 3410);
DISPLAY 0.659574 (-3190 3410);
PAINT MONO (-3190 3410);
DISPLAY INVISIBLE (-3190 3410);
FORCEPROP 1 LASTPIN (-3200 3400) BN 3
J 0
(-3250 3410);
DISPLAY 0.617021 (-3250 3410);
PAINT PINK (-3250 3410);
FORCEPROP 2 LAST CDS_LIB mstr_standard
J 0
(-3250 3400);
DISPLAY 0.787234 (-3250 3400);
PAINT MONO (-3250 3400);
DISPLAY INVISIBLE (-3250 3400);
FORCEPROP 1 LAST BODY_TYPE PLUMBING
J 0
(-3250 3350);
DISPLAY 1.234043 (-3250 3350);
PAINT GREEN (-3250 3350);
DISPLAY INVISIBLE (-3250 3350);
FORCEPROP 1 LAST HDL_TAP TRUE
J 0
(-2925 3275);
DISPLAY 1.234043 (-2925 3275);
PAINT GREEN (-2925 3275);
DISPLAY INVISIBLE (-2925 3275);
FORCEPROP 1 LAST PATH I159
J 0
(-3250 3400);
DISPLAY 0.936170 (-3250 3400);
PAINT GREEN (-3250 3400);
DISPLAY INVISIBLE (-3250 3400);
FORCEADD PVDDQ_KLM..1
(-1350 2625);
FORCEPROP 3 LASTPIN (-1350 2575) SIG_NAME PVDDQ_KLM\g
J 0
(-1340 2585);
DISPLAY 0.659574 (-1340 2585);
PAINT MONO (-1340 2585);
DISPLAY INVISIBLE (-1340 2585);
FORCEPROP 1 LAST VOLTAGE 1.2V
J 0
(-1395 2582);
DISPLAY 0.340426 (-1395 2582);
PAINT SKYBLUE (-1395 2582);
DISPLAY INVISIBLE (-1395 2582);
FORCEPROP 2 LAST BOM_COST MEM
J 0
(-1350 2630);
PAINT ORANGE (-1350 2630);
DISPLAY INVISIBLE (-1350 2630);
FORCEPROP 2 LAST CDS_LIB mstr_symbols
J 0
(-1350 2625);
PAINT ORANGE (-1350 2625);
DISPLAY INVISIBLE (-1350 2625);
FORCEPROP 1 LAST BODY_TYPE PLUMBING
J 0
(-1395 2582);
DISPLAY 0.340426 (-1395 2582);
PAINT GREEN (-1395 2582);
DISPLAY INVISIBLE (-1395 2582);
FORCEPROP 1 LAST PATH I16
J 0
(-1300 2650);
DISPLAY 0.872340 (-1300 2650);
PAINT AQUA (-1300 2650);
DISPLAY INVISIBLE (-1300 2650);
FORCEPROP 2 LAST ROOM DDR4_CH_D
J 0
(-1350 2725);
DISPLAY 0.787234 (-1350 2725);
PAINT ORANGE (-1350 2725);
DISPLAY INVISIBLE (-1350 2725);
FORCEPROP 1 LAST HDL_POWER PVDDQ_KLM
J 1
(-1350 2675);
DISPLAY 0.872340 (-1350 2675);
PAINT GREEN (-1350 2675);
DISPLAY INVISIBLE (-1350 2675);
FORCEADD TAP..6
(-3250 3350);
FORCEPROP 3 LASTPIN (-3200 3350) SIG_NAME M_L_CS_N<2>
J 0
(-3190 3360);
DISPLAY 0.659574 (-3190 3360);
PAINT MONO (-3190 3360);
DISPLAY INVISIBLE (-3190 3360);
FORCEPROP 1 LASTPIN (-3200 3350) BN 2
J 0
(-3250 3360);
DISPLAY 0.617021 (-3250 3360);
PAINT PINK (-3250 3360);
FORCEPROP 2 LAST CDS_LIB mstr_standard
J 0
(-3250 3350);
DISPLAY 0.787234 (-3250 3350);
PAINT MONO (-3250 3350);
DISPLAY INVISIBLE (-3250 3350);
FORCEPROP 1 LAST BODY_TYPE PLUMBING
J 0
(-3250 3300);
DISPLAY 1.234043 (-3250 3300);
PAINT GREEN (-3250 3300);
DISPLAY INVISIBLE (-3250 3300);
FORCEPROP 1 LAST HDL_TAP TRUE
J 0
(-2925 3225);
DISPLAY 1.234043 (-2925 3225);
PAINT GREEN (-2925 3225);
DISPLAY INVISIBLE (-2925 3225);
FORCEPROP 1 LAST PATH I160
J 0
(-3250 3350);
DISPLAY 0.936170 (-3250 3350);
PAINT GREEN (-3250 3350);
DISPLAY INVISIBLE (-3250 3350);
FORCEADD TAP..6
(-3250 3300);
FORCEPROP 3 LASTPIN (-3200 3300) SIG_NAME M_L_CS_N<1>
J 0
(-3190 3310);
DISPLAY 0.659574 (-3190 3310);
PAINT MONO (-3190 3310);
DISPLAY INVISIBLE (-3190 3310);
FORCEPROP 1 LASTPIN (-3200 3300) BN 1
J 0
(-3250 3310);
DISPLAY 0.617021 (-3250 3310);
PAINT PINK (-3250 3310);
FORCEPROP 2 LAST CDS_LIB mstr_standard
J 0
(-3250 3300);
DISPLAY 0.787234 (-3250 3300);
PAINT MONO (-3250 3300);
DISPLAY INVISIBLE (-3250 3300);
FORCEPROP 1 LAST BODY_TYPE PLUMBING
J 0
(-3250 3250);
DISPLAY 1.234043 (-3250 3250);
PAINT GREEN (-3250 3250);
DISPLAY INVISIBLE (-3250 3250);
FORCEPROP 1 LAST HDL_TAP TRUE
J 0
(-2925 3175);
DISPLAY 1.234043 (-2925 3175);
PAINT GREEN (-2925 3175);
DISPLAY INVISIBLE (-2925 3175);
FORCEPROP 1 LAST PATH I161
J 0
(-3250 3300);
DISPLAY 0.936170 (-3250 3300);
PAINT GREEN (-3250 3300);
DISPLAY INVISIBLE (-3250 3300);
FORCEADD TAP..6
(-3250 3250);
FORCEPROP 3 LASTPIN (-3200 3250) SIG_NAME M_L_CS_N<0>
J 0
(-3190 3260);
DISPLAY 0.659574 (-3190 3260);
PAINT MONO (-3190 3260);
DISPLAY INVISIBLE (-3190 3260);
FORCEPROP 1 LASTPIN (-3200 3250) BN 0
J 0
(-3250 3260);
DISPLAY 0.617021 (-3250 3260);
PAINT PINK (-3250 3260);
FORCEPROP 2 LAST CDS_LIB mstr_standard
J 0
(-3250 3250);
DISPLAY 0.787234 (-3250 3250);
PAINT MONO (-3250 3250);
DISPLAY INVISIBLE (-3250 3250);
FORCEPROP 1 LAST BODY_TYPE PLUMBING
J 0
(-3250 3200);
DISPLAY 1.234043 (-3250 3200);
PAINT GREEN (-3250 3200);
DISPLAY INVISIBLE (-3250 3200);
FORCEPROP 1 LAST HDL_TAP TRUE
J 0
(-2925 3125);
DISPLAY 1.234043 (-2925 3125);
PAINT GREEN (-2925 3125);
DISPLAY INVISIBLE (-2925 3125);
FORCEPROP 1 LAST PATH I162
J 0
(-3250 3250);
DISPLAY 0.936170 (-3250 3250);
PAINT GREEN (-3250 3250);
DISPLAY INVISIBLE (-3250 3250);
FORCEADD TAP..6
(-3250 3150);
FORCEPROP 3 LASTPIN (-3200 3150) SIG_NAME M_L_CKE<1>
J 0
(-3190 3160);
DISPLAY 0.659574 (-3190 3160);
PAINT MONO (-3190 3160);
DISPLAY INVISIBLE (-3190 3160);
FORCEPROP 1 LASTPIN (-3200 3150) BN 1
J 0
(-3250 3160);
DISPLAY 0.617021 (-3250 3160);
PAINT PINK (-3250 3160);
FORCEPROP 2 LAST CDS_LIB mstr_standard
J 0
(-3250 3150);
DISPLAY 0.787234 (-3250 3150);
PAINT MONO (-3250 3150);
DISPLAY INVISIBLE (-3250 3150);
FORCEPROP 1 LAST BODY_TYPE PLUMBING
J 0
(-3250 3100);
DISPLAY 1.234043 (-3250 3100);
PAINT GREEN (-3250 3100);
DISPLAY INVISIBLE (-3250 3100);
FORCEPROP 1 LAST HDL_TAP TRUE
J 0
(-2925 3025);
DISPLAY 1.234043 (-2925 3025);
PAINT GREEN (-2925 3025);
DISPLAY INVISIBLE (-2925 3025);
FORCEPROP 1 LAST PATH I163
J 0
(-3250 3150);
DISPLAY 0.936170 (-3250 3150);
PAINT GREEN (-3250 3150);
DISPLAY INVISIBLE (-3250 3150);
FORCEADD OFFPAGE..1
(-3850 3450);
FORCEPROP 2 LAST $XR0 61 
J 0
(-4101 3450);
DISPLAY 0.638298 (-4101 3450);
PAINT MONO (-4101 3450);
FORCEPROP 2 LAST $XR1 86 
J 0
(-4191 3450);
DISPLAY 0.638298 (-4191 3450);
PAINT MONO (-4191 3450);
FORCEPROP 2 LAST CDS_LIB mstr_standard
J 0
(-3850 3450);
DISPLAY 0.787234 (-3850 3450);
PAINT MONO (-3850 3450);
DISPLAY INVISIBLE (-3850 3450);
FORCEPROP 1 LAST OFFPAGE TRUE
J 0
(-3525 3325);
DISPLAY 0.936170 (-3525 3325);
PAINT GREEN (-3525 3325);
DISPLAY INVISIBLE (-3525 3325);
FORCEPROP 1 LAST COMMENT_BODY TRUE
J 0
(-3725 3350);
DISPLAY 0.936170 (-3725 3350);
PAINT GREEN (-3725 3350);
DISPLAY INVISIBLE (-3725 3350);
FORCEPROP 2 LAST PATH I164
J 0
(-3800 3525);
DISPLAY 0.787234 (-3800 3525);
PAINT MONO (-3800 3525);
DISPLAY INVISIBLE (-3800 3525);
FORCEADD OFFPAGE..1
(-3850 3200);
FORCEPROP 2 LAST $XR0 61 
J 0
(-4101 3200);
DISPLAY 0.638298 (-4101 3200);
PAINT MONO (-4101 3200);
FORCEPROP 2 LAST $XR1 86 
J 0
(-4191 3200);
DISPLAY 0.638298 (-4191 3200);
PAINT MONO (-4191 3200);
FORCEPROP 2 LAST CDS_LIB mstr_standard
J 0
(-3850 3200);
DISPLAY 0.787234 (-3850 3200);
PAINT MONO (-3850 3200);
DISPLAY INVISIBLE (-3850 3200);
FORCEPROP 1 LAST OFFPAGE TRUE
J 0
(-3525 3075);
DISPLAY 0.936170 (-3525 3075);
PAINT GREEN (-3525 3075);
DISPLAY INVISIBLE (-3525 3075);
FORCEPROP 1 LAST COMMENT_BODY TRUE
J 0
(-3725 3100);
DISPLAY 0.936170 (-3725 3100);
PAINT GREEN (-3725 3100);
DISPLAY INVISIBLE (-3725 3100);
FORCEPROP 2 LAST PATH I165
J 0
(-3800 3275);
DISPLAY 0.787234 (-3800 3275);
PAINT MONO (-3800 3275);
DISPLAY INVISIBLE (-3800 3275);
FORCEADD TAP..6
(-3250 3100);
FORCEPROP 3 LASTPIN (-3200 3100) SIG_NAME M_L_CKE<0>
J 0
(-3190 3110);
DISPLAY 0.659574 (-3190 3110);
PAINT MONO (-3190 3110);
DISPLAY INVISIBLE (-3190 3110);
FORCEPROP 1 LASTPIN (-3200 3100) BN 0
J 0
(-3250 3110);
DISPLAY 0.617021 (-3250 3110);
PAINT PINK (-3250 3110);
FORCEPROP 2 LAST CDS_LIB mstr_standard
J 0
(-3250 3100);
DISPLAY 0.787234 (-3250 3100);
PAINT MONO (-3250 3100);
DISPLAY INVISIBLE (-3250 3100);
FORCEPROP 1 LAST BODY_TYPE PLUMBING
J 0
(-3250 3050);
DISPLAY 1.234043 (-3250 3050);
PAINT GREEN (-3250 3050);
DISPLAY INVISIBLE (-3250 3050);
FORCEPROP 1 LAST HDL_TAP TRUE
J 0
(-2925 2975);
DISPLAY 1.234043 (-2925 2975);
PAINT GREEN (-2925 2975);
DISPLAY INVISIBLE (-2925 2975);
FORCEPROP 1 LAST PATH I166
J 0
(-3250 3100);
DISPLAY 0.936170 (-3250 3100);
PAINT GREEN (-3250 3100);
DISPLAY INVISIBLE (-3250 3100);
FORCEADD TAP..6
(-3250 3000);
FORCEPROP 3 LASTPIN (-3200 3000) SIG_NAME M_L_ODT<1>
J 0
(-3190 3010);
DISPLAY 0.659574 (-3190 3010);
PAINT MONO (-3190 3010);
DISPLAY INVISIBLE (-3190 3010);
FORCEPROP 1 LASTPIN (-3200 3000) BN 1
J 0
(-3250 3010);
DISPLAY 0.617021 (-3250 3010);
PAINT PINK (-3250 3010);
FORCEPROP 2 LAST CDS_LIB mstr_standard
J 0
(-3250 3000);
DISPLAY 0.787234 (-3250 3000);
PAINT MONO (-3250 3000);
DISPLAY INVISIBLE (-3250 3000);
FORCEPROP 1 LAST BODY_TYPE PLUMBING
J 0
(-3250 2950);
DISPLAY 1.234043 (-3250 2950);
PAINT GREEN (-3250 2950);
DISPLAY INVISIBLE (-3250 2950);
FORCEPROP 1 LAST HDL_TAP TRUE
J 0
(-2925 2875);
DISPLAY 1.234043 (-2925 2875);
PAINT GREEN (-2925 2875);
DISPLAY INVISIBLE (-2925 2875);
FORCEPROP 1 LAST PATH I167
J 0
(-3250 3000);
DISPLAY 0.936170 (-3250 3000);
PAINT GREEN (-3250 3000);
DISPLAY INVISIBLE (-3250 3000);
FORCEADD TAP..6
(-3250 2950);
FORCEPROP 3 LASTPIN (-3200 2950) SIG_NAME M_L_ODT<0>
J 0
(-3190 2960);
DISPLAY 0.659574 (-3190 2960);
PAINT MONO (-3190 2960);
DISPLAY INVISIBLE (-3190 2960);
FORCEPROP 1 LASTPIN (-3200 2950) BN 0
J 0
(-3250 2960);
DISPLAY 0.617021 (-3250 2960);
PAINT PINK (-3250 2960);
FORCEPROP 2 LAST CDS_LIB mstr_standard
J 0
(-3250 2950);
DISPLAY 0.787234 (-3250 2950);
PAINT MONO (-3250 2950);
DISPLAY INVISIBLE (-3250 2950);
FORCEPROP 1 LAST BODY_TYPE PLUMBING
J 0
(-3250 2900);
DISPLAY 1.234043 (-3250 2900);
PAINT GREEN (-3250 2900);
DISPLAY INVISIBLE (-3250 2900);
FORCEPROP 1 LAST HDL_TAP TRUE
J 0
(-2925 2825);
DISPLAY 1.234043 (-2925 2825);
PAINT GREEN (-2925 2825);
DISPLAY INVISIBLE (-2925 2825);
FORCEPROP 1 LAST PATH I168
J 0
(-3250 2950);
DISPLAY 0.936170 (-3250 2950);
PAINT GREEN (-3250 2950);
DISPLAY INVISIBLE (-3250 2950);
FORCEADD OFFPAGE..1
(-3850 3050);
FORCEPROP 2 LAST $XR0 61 
J 0
(-4101 3050);
DISPLAY 0.638298 (-4101 3050);
PAINT MONO (-4101 3050);
FORCEPROP 2 LAST $XR1 86 
J 0
(-4191 3050);
DISPLAY 0.638298 (-4191 3050);
PAINT MONO (-4191 3050);
FORCEPROP 2 LAST CDS_LIB mstr_standard
J 0
(-3850 3050);
DISPLAY 0.787234 (-3850 3050);
PAINT MONO (-3850 3050);
DISPLAY INVISIBLE (-3850 3050);
FORCEPROP 1 LAST OFFPAGE TRUE
J 0
(-3525 2925);
DISPLAY 0.936170 (-3525 2925);
PAINT GREEN (-3525 2925);
DISPLAY INVISIBLE (-3525 2925);
FORCEPROP 1 LAST COMMENT_BODY TRUE
J 0
(-3725 2950);
DISPLAY 0.936170 (-3725 2950);
PAINT GREEN (-3725 2950);
DISPLAY INVISIBLE (-3725 2950);
FORCEPROP 2 LAST PATH I169
J 0
(-3800 3125);
DISPLAY 0.787234 (-3800 3125);
PAINT MONO (-3800 3125);
DISPLAY INVISIBLE (-3800 3125);
FORCEADD PVTT_KLM..1
(-1100 2750);
FORCEPROP 3 LASTPIN (-1100 2700) SIG_NAME PVTT_KLM\g
J 0
(-1090 2710);
DISPLAY 0.659574 (-1090 2710);
PAINT MONO (-1090 2710);
DISPLAY INVISIBLE (-1090 2710);
FORCEPROP 1 LAST VOLTAGE 0.6V
J 0
(-1145 2707);
DISPLAY 0.340426 (-1145 2707);
PAINT SKYBLUE (-1145 2707);
DISPLAY INVISIBLE (-1145 2707);
FORCEPROP 2 LAST BOM_COST MEM
J 0
(-1100 2755);
PAINT ORANGE (-1100 2755);
DISPLAY INVISIBLE (-1100 2755);
FORCEPROP 2 LAST CDS_LIB mstr_symbols
J 0
(-1100 2750);
PAINT ORANGE (-1100 2750);
DISPLAY INVISIBLE (-1100 2750);
FORCEPROP 1 LAST BODY_TYPE PLUMBING
J 0
(-1145 2707);
DISPLAY 0.340426 (-1145 2707);
PAINT GREEN (-1145 2707);
DISPLAY INVISIBLE (-1145 2707);
FORCEPROP 1 LAST PATH I17
J 0
(-1050 2775);
DISPLAY 0.872340 (-1050 2775);
PAINT AQUA (-1050 2775);
DISPLAY INVISIBLE (-1050 2775);
FORCEPROP 2 LAST ROOM DDR4_CH_D
J 0
(-1100 2850);
DISPLAY 0.787234 (-1100 2850);
PAINT ORANGE (-1100 2850);
DISPLAY INVISIBLE (-1100 2850);
FORCEPROP 1 LAST HDL_POWER PVTT_KLM
J 1
(-1100 2800);
DISPLAY 0.872340 (-1100 2800);
PAINT GREEN (-1100 2800);
DISPLAY INVISIBLE (-1100 2800);
FORCEADD SCONN288_H44441004..4
(-250 2050);
FORCEPROP 1 LAST LOCATION J1A2
J 0
(-700 3150);
DISPLAY 0.617021 (-700 3150);
PAINT AQUA (-700 3150);
FORCEPROP 1 LAST PART_NUMBER H44441-004
J 0
(-700 1000);
DISPLAY 0.617021 (-700 1000);
PAINT BLUE (-700 1000);
FORCEPROP 1 LAST MATERIAL SCONN
J 0
(-700 3100);
DISPLAY 0.617021 (-700 3100);
PAINT SKYBLUE (-700 3100);
FORCEPROP 2 LASTPIN (-750 2600) $PN 77
J 2
(-760 2610);
DISPLAY 0.617021 (-760 2610);
PAINT ORANGE (-760 2610);
FORCEPROP 2 LASTPIN (-750 2550) $PN 221
J 2
(-760 2560);
DISPLAY 0.617021 (-760 2560);
PAINT ORANGE (-760 2560);
FORCEPROP 2 LASTPIN (-750 2900) $PN 142
J 2
(-760 2910);
DISPLAY 0.617021 (-760 2910);
PAINT ORANGE (-760 2910);
FORCEPROP 2 LASTPIN (-750 2850) $PN 143
J 2
(-760 2860);
DISPLAY 0.617021 (-760 2860);
PAINT ORANGE (-760 2860);
FORCEPROP 2 LASTPIN (-750 2800) $PN 288
J 2
(-760 2810);
DISPLAY 0.617021 (-760 2810);
PAINT ORANGE (-760 2810);
FORCEPROP 2 LASTPIN (-750 2750) $PN 286
J 2
(-760 2760);
DISPLAY 0.617021 (-760 2760);
PAINT ORANGE (-760 2760);
FORCEPROP 2 LASTPIN (-750 2700) $PN 287
J 2
(-760 2710);
DISPLAY 0.617021 (-760 2710);
PAINT ORANGE (-760 2710);
FORCEPROP 2 LASTPIN (-750 2450) $PN 59
J 2
(-760 2460);
DISPLAY 0.617021 (-760 2460);
PAINT ORANGE (-760 2460);
FORCEPROP 2 LASTPIN (-750 2400) $PN 61
J 2
(-760 2410);
DISPLAY 0.617021 (-760 2410);
PAINT ORANGE (-760 2410);
FORCEPROP 2 LASTPIN (-750 2350) $PN 64
J 2
(-760 2360);
DISPLAY 0.617021 (-760 2360);
PAINT ORANGE (-760 2360);
FORCEPROP 2 LASTPIN (-750 2300) $PN 67
J 2
(-760 2310);
DISPLAY 0.617021 (-760 2310);
PAINT ORANGE (-760 2310);
FORCEPROP 2 LASTPIN (-750 2250) $PN 70
J 2
(-760 2260);
DISPLAY 0.617021 (-760 2260);
PAINT ORANGE (-760 2260);
FORCEPROP 2 LASTPIN (-750 2200) $PN 73
J 2
(-760 2210);
DISPLAY 0.617021 (-760 2210);
PAINT ORANGE (-760 2210);
FORCEPROP 2 LASTPIN (-750 2150) $PN 76
J 2
(-760 2160);
DISPLAY 0.617021 (-760 2160);
PAINT ORANGE (-760 2160);
FORCEPROP 2 LASTPIN (-750 2100) $PN 80
J 2
(-760 2110);
DISPLAY 0.617021 (-760 2110);
PAINT ORANGE (-760 2110);
FORCEPROP 2 LASTPIN (-750 2050) $PN 83
J 2
(-760 2060);
DISPLAY 0.617021 (-760 2060);
PAINT ORANGE (-760 2060);
FORCEPROP 2 LASTPIN (-750 2000) $PN 85
J 2
(-760 2010);
DISPLAY 0.617021 (-760 2010);
PAINT ORANGE (-760 2010);
FORCEPROP 2 LASTPIN (-750 1950) $PN 88
J 2
(-760 1960);
DISPLAY 0.617021 (-760 1960);
PAINT ORANGE (-760 1960);
FORCEPROP 2 LASTPIN (-750 1900) $PN 90
J 2
(-760 1910);
DISPLAY 0.617021 (-760 1910);
PAINT ORANGE (-760 1910);
FORCEPROP 2 LASTPIN (-750 1850) $PN 92
J 2
(-760 1860);
DISPLAY 0.617021 (-760 1860);
PAINT ORANGE (-760 1860);
FORCEPROP 2 LASTPIN (-750 1800) $PN 204
J 2
(-760 1810);
DISPLAY 0.617021 (-760 1810);
PAINT ORANGE (-760 1810);
FORCEPROP 2 LASTPIN (-750 1750) $PN 206
J 2
(-760 1760);
DISPLAY 0.617021 (-760 1760);
PAINT ORANGE (-760 1760);
FORCEPROP 2 LASTPIN (-750 1700) $PN 209
J 2
(-760 1710);
DISPLAY 0.617021 (-760 1710);
PAINT ORANGE (-760 1710);
FORCEPROP 2 LASTPIN (-750 1650) $PN 212
J 2
(-760 1660);
DISPLAY 0.617021 (-760 1660);
PAINT ORANGE (-760 1660);
FORCEPROP 2 LASTPIN (-750 1600) $PN 215
J 2
(-760 1610);
DISPLAY 0.617021 (-760 1610);
PAINT ORANGE (-760 1610);
FORCEPROP 2 LASTPIN (-750 1550) $PN 217
J 2
(-760 1560);
DISPLAY 0.617021 (-760 1560);
PAINT ORANGE (-760 1560);
FORCEPROP 2 LASTPIN (-750 1500) $PN 220
J 2
(-760 1510);
DISPLAY 0.617021 (-760 1510);
PAINT ORANGE (-760 1510);
FORCEPROP 2 LASTPIN (-750 1450) $PN 223
J 2
(-760 1460);
DISPLAY 0.617021 (-760 1460);
PAINT ORANGE (-760 1460);
FORCEPROP 2 LASTPIN (-750 1400) $PN 226
J 2
(-760 1410);
DISPLAY 0.617021 (-760 1410);
PAINT ORANGE (-760 1410);
FORCEPROP 2 LASTPIN (-750 1350) $PN 229
J 2
(-760 1360);
DISPLAY 0.617021 (-760 1360);
PAINT ORANGE (-760 1360);
FORCEPROP 2 LASTPIN (-750 1300) $PN 231
J 2
(-760 1310);
DISPLAY 0.617021 (-760 1310);
PAINT ORANGE (-760 1310);
FORCEPROP 2 LASTPIN (-750 1250) $PN 233
J 2
(-760 1260);
DISPLAY 0.617021 (-760 1260);
PAINT ORANGE (-760 1260);
FORCEPROP 2 LASTPIN (-750 1200) $PN 236
J 2
(-760 1210);
DISPLAY 0.617021 (-760 1210);
PAINT ORANGE (-760 1210);
FORCEPROP 2 LASTPIN (250 2900) $PN 1
J 0
(260 2910);
DISPLAY 0.617021 (260 2910);
PAINT ORANGE (260 2910);
FORCEPROP 2 LASTPIN (250 2850) $PN 145
J 0
(260 2860);
DISPLAY 0.617021 (260 2860);
PAINT ORANGE (260 2860);
FORCEPROP 1 LAST PACK_TYPE PIP
J 0
(-700 3200);
PAINT SKYBLUE (-700 3200);
DISPLAY INVISIBLE (-700 3200);
FORCEPROP 2 LAST BOM_COST MEM
J 0
(-250 2050);
PAINT ORANGE (-250 2050);
DISPLAY INVISIBLE (-250 2050);
FORCEPROP 2 LAST CDS_LIB mstr_sconn
J 0
(-250 2050);
PAINT ORANGE (-250 2050);
DISPLAY INVISIBLE (-250 2050);
FORCEPROP 2 LAST SEC_TYPE PIP
J 0
(-700 3200);
DISPLAY 1.021277 (-700 3200);
PAINT ORANGE (-700 3200);
DISPLAY INVISIBLE (-700 3200);
FORCEPROP 2 LAST SEC 4
J 0
(-700 3200);
DISPLAY 0.680851 (-700 3200);
PAINT MONO (-700 3200);
DISPLAY INVISIBLE (-700 3200);
FORCEPROP 2 LAST CDS_LOCATION J1A2
J 0
(-700 3150);
DISPLAY 0.617021 (-700 3150);
PAINT AQUA (-700 3150);
DISPLAY INVISIBLE (-700 3150);
FORCEPROP 1 LAST PATH I172
J 0
(-250 3100);
PAINT GREEN (-250 3100);
DISPLAY INVISIBLE (-250 3100);
FORCEPROP 2 LAST ROOM DDR4_CH_L
J 0
(-250 2050);
PAINT ORANGE (-250 2050);
DISPLAY INVISIBLE (-250 2050);
FORCEADD GND..1
R 2
(2500 1100);
FORCEPROP 3 LASTPIN (2500 1150) SIG_NAME GND\g
J 0
(2510 1160);
DISPLAY 0.659574 (2510 1160);
PAINT MONO (2510 1160);
DISPLAY INVISIBLE (2510 1160);
FORCEPROP 1 LAST VOLTAGE 0
J 0
(2500 1100);
PAINT SKYBLUE (2500 1100);
DISPLAY INVISIBLE (2500 1100);
FORCEPROP 2 LAST BOM_COST MEM
J 0
(2500 1105);
PAINT ORANGE (2500 1105);
DISPLAY INVISIBLE (2500 1105);
FORCEPROP 2 LAST CDS_LIB mstr_symbols
J 0
(2500 1100);
DISPLAY 0.787234 (2500 1100);
PAINT MONO (2500 1100);
DISPLAY INVISIBLE (2500 1100);
FORCEPROP 1 LAST SIZE 1B
J 2
(2425 1050);
DISPLAY 1.170213 (2425 1050);
PAINT GREEN (2425 1050);
DISPLAY INVISIBLE (2425 1050);
FORCEPROP 1 LAST BODY_TYPE PLUMBING
J 2
(2545 1057);
DISPLAY 0.340426 (2545 1057);
PAINT GREEN (2545 1057);
DISPLAY INVISIBLE (2545 1057);
FORCEPROP 1 LAST PATH I173
J 2
(2425 1100);
DISPLAY 1.404255 (2425 1100);
PAINT GREEN (2425 1100);
DISPLAY INVISIBLE (2425 1100);
FORCEPROP 2 LAST ROOM DDR4_CH_D
J 0
(2500 1105);
PAINT ORANGE (2500 1105);
DISPLAY INVISIBLE (2500 1105);
FORCEPROP 1 LAST HDL_POWER GND
J 2
(2500 1250);
DISPLAY 0.553191 (2500 1250);
PAINT GREEN (2500 1250);
DISPLAY INVISIBLE (2500 1250);
FORCEADD GND..1
R 2
(-5150 1850);
FORCEPROP 3 LASTPIN (-5150 1900) SIG_NAME GND\g
J 0
(-5140 1910);
DISPLAY 0.659574 (-5140 1910);
PAINT MONO (-5140 1910);
DISPLAY INVISIBLE (-5140 1910);
FORCEPROP 1 LAST VOLTAGE 0
J 0
(-5150 1850);
PAINT SKYBLUE (-5150 1850);
DISPLAY INVISIBLE (-5150 1850);
FORCEPROP 2 LAST BOM_COST MEM
J 0
(-5150 1855);
PAINT ORANGE (-5150 1855);
DISPLAY INVISIBLE (-5150 1855);
FORCEPROP 1 LAST SIZE 1B
J 2
(-5225 1800);
DISPLAY 1.170213 (-5225 1800);
PAINT GREEN (-5225 1800);
DISPLAY INVISIBLE (-5225 1800);
FORCEPROP 2 LAST CDS_LIB mstr_symbols
J 0
(-5150 1850);
DISPLAY 0.787234 (-5150 1850);
PAINT MONO (-5150 1850);
DISPLAY INVISIBLE (-5150 1850);
FORCEPROP 1 LAST BODY_TYPE PLUMBING
J 2
(-5105 1807);
DISPLAY 0.340426 (-5105 1807);
PAINT GREEN (-5105 1807);
DISPLAY INVISIBLE (-5105 1807);
FORCEPROP 1 LAST PATH I175
J 2
(-5225 1850);
DISPLAY 1.404255 (-5225 1850);
PAINT GREEN (-5225 1850);
DISPLAY INVISIBLE (-5225 1850);
FORCEPROP 2 LAST ROOM DDR4_CH_D
J 0
(-5150 1855);
PAINT ORANGE (-5150 1855);
DISPLAY INVISIBLE (-5150 1855);
FORCEPROP 1 LAST HDL_POWER GND
J 2
(-5150 2000);
DISPLAY 0.553191 (-5150 2000);
PAINT GREEN (-5150 2000);
DISPLAY INVISIBLE (-5150 2000);
FORCEADD OFFPAGE..6
(-3850 1900);
FORCEPROP 2 LAST $XR0 83 
J 0
(-4099 1900);
DISPLAY 0.638298 (-4099 1900);
PAINT MONO (-4099 1900);
FORCEPROP 2 LAST $XR1 84 
J 0
(-4189 1900);
DISPLAY 0.638298 (-4189 1900);
PAINT MONO (-4189 1900);
FORCEPROP 2 LAST $XR2 86 
J 0
(-4279 1900);
DISPLAY 0.638298 (-4279 1900);
PAINT MONO (-4279 1900);
FORCEPROP 2 LAST $XR3 87 
J 0
(-4369 1900);
DISPLAY 0.638298 (-4369 1900);
PAINT MONO (-4369 1900);
FORCEPROP 2 LAST $XR4 88 
J 0
(-4459 1900);
DISPLAY 0.638298 (-4459 1900);
PAINT MONO (-4459 1900);
FORCEPROP 2 LAST $XR5 99 
J 0
(-4549 1900);
DISPLAY 0.638298 (-4549 1900);
PAINT MONO (-4549 1900);
FORCEPROP 2 LASTPIN (-3800 1900) SIG_NAME SMB_DDR_KLM_VPP_SDA
J 0
(-3760 1910);
DISPLAY 0.617021 (-3760 1910);
PAINT ORANGE (-3760 1910);
FORCEPROP 2 LAST CDS_LIB mstr_standard
J 0
(-3850 1900);
DISPLAY 0.787234 (-3850 1900);
PAINT MONO (-3850 1900);
DISPLAY INVISIBLE (-3850 1900);
FORCEPROP 1 LAST OFFPAGE TRUE
J 0
(-3525 1775);
DISPLAY 0.936170 (-3525 1775);
PAINT GREEN (-3525 1775);
DISPLAY INVISIBLE (-3525 1775);
FORCEPROP 1 LAST COMMENT_BODY TRUE
J 0
(-3750 1825);
DISPLAY 0.936170 (-3750 1825);
PAINT GREEN (-3750 1825);
DISPLAY INVISIBLE (-3750 1825);
FORCEPROP 2 LAST PATH I176
J 0
(-4150 1950);
DISPLAY 0.787234 (-4150 1950);
PAINT ORANGE (-4150 1950);
DISPLAY INVISIBLE (-4150 1950);
FORCEADD OFFPAGE..1
(-4800 1750);
FORCEPROP 2 LAST $XR0 100 
J 0
(-5082 1750);
DISPLAY 0.638298 (-5082 1750);
PAINT MONO (-5082 1750);
FORCEPROP 2 LAST $XR1 86 
J 0
(-5172 1750);
DISPLAY 0.638298 (-5172 1750);
PAINT MONO (-5172 1750);
FORCEPROP 2 LAST CDS_LIB mstr_standard
J 0
(-4800 1750);
DISPLAY 0.787234 (-4800 1750);
PAINT MONO (-4800 1750);
DISPLAY INVISIBLE (-4800 1750);
FORCEPROP 1 LAST OFFPAGE TRUE
J 0
(-4475 1625);
DISPLAY 0.936170 (-4475 1625);
PAINT GREEN (-4475 1625);
DISPLAY INVISIBLE (-4475 1625);
FORCEPROP 1 LAST COMMENT_BODY TRUE
J 0
(-4675 1650);
DISPLAY 0.936170 (-4675 1650);
PAINT GREEN (-4675 1650);
DISPLAY INVISIBLE (-4675 1650);
FORCEPROP 2 LAST PATH I177
J 0
(-5050 1800);
DISPLAY 0.787234 (-5050 1800);
PAINT ORANGE (-5050 1800);
DISPLAY INVISIBLE (-5050 1800);
FORCEADD OFFPAGE..1
(-3850 1850);
FORCEPROP 2 LAST $XR0 99 
J 0
(-4101 1850);
DISPLAY 0.638298 (-4101 1850);
PAINT MONO (-4101 1850);
FORCEPROP 2 LAST $XR1 83 
J 0
(-4191 1850);
DISPLAY 0.638298 (-4191 1850);
PAINT MONO (-4191 1850);
FORCEPROP 2 LAST $XR2 84 
J 0
(-4281 1850);
DISPLAY 0.638298 (-4281 1850);
PAINT MONO (-4281 1850);
FORCEPROP 2 LAST $XR3 86 
J 0
(-4371 1850);
DISPLAY 0.638298 (-4371 1850);
PAINT MONO (-4371 1850);
FORCEPROP 2 LAST $XR4 87 
J 0
(-4461 1850);
DISPLAY 0.638298 (-4461 1850);
PAINT MONO (-4461 1850);
FORCEPROP 2 LAST $XR5 88 
J 0
(-4551 1850);
DISPLAY 0.638298 (-4551 1850);
PAINT MONO (-4551 1850);
FORCEPROP 2 LAST CDS_LIB mstr_standard
J 0
(-3850 1850);
DISPLAY 0.787234 (-3850 1850);
PAINT MONO (-3850 1850);
DISPLAY INVISIBLE (-3850 1850);
FORCEPROP 1 LAST OFFPAGE TRUE
J 0
(-3525 1725);
DISPLAY 0.936170 (-3525 1725);
PAINT GREEN (-3525 1725);
DISPLAY INVISIBLE (-3525 1725);
FORCEPROP 1 LAST COMMENT_BODY TRUE
J 0
(-3725 1750);
DISPLAY 0.936170 (-3725 1750);
PAINT GREEN (-3725 1750);
DISPLAY INVISIBLE (-3725 1750);
FORCEPROP 2 LAST PATH I178
J 0
(-4125 1900);
DISPLAY 0.787234 (-4125 1900);
PAINT ORANGE (-4125 1900);
DISPLAY INVISIBLE (-4125 1900);
FORCEADD OFFPAGE..5
(-4225 2550);
FORCEPROP 2 LAST $XR0 43 
J 0
(-4449 2550);
DISPLAY 0.638298 (-4449 2550);
PAINT MONO (-4449 2550);
FORCEPROP 2 LAST $XR1 44 
J 0
(-4539 2550);
DISPLAY 0.638298 (-4539 2550);
PAINT MONO (-4539 2550);
FORCEPROP 2 LAST $XR2 45 
J 0
(-4629 2550);
DISPLAY 0.638298 (-4629 2550);
PAINT MONO (-4629 2550);
FORCEPROP 2 LAST $XR3 46 
J 0
(-4719 2550);
DISPLAY 0.638298 (-4719 2550);
PAINT MONO (-4719 2550);
FORCEPROP 2 LAST $XR4 47 
J 0
(-4809 2550);
DISPLAY 0.638298 (-4809 2550);
PAINT MONO (-4809 2550);
FORCEPROP 2 LAST $XR5 48 
J 0
(-4899 2550);
DISPLAY 0.638298 (-4899 2550);
PAINT MONO (-4899 2550);
FORCEPROP 2 LAST $XR6 49 
J 0
(-4989 2550);
DISPLAY 0.638298 (-4989 2550);
PAINT MONO (-4989 2550);
FORCEPROP 2 LAST $XR7 50 
J 0
(-5079 2550);
DISPLAY 0.638298 (-5079 2550);
PAINT MONO (-5079 2550);
FORCEPROP 2 LAST $XR8 51 
J 0
(-5169 2550);
DISPLAY 0.638298 (-5169 2550);
PAINT MONO (-5169 2550);
FORCEPROP 2 LAST $XR9 52 
J 0
(-5259 2550);
DISPLAY 0.638298 (-5259 2550);
PAINT MONO (-5259 2550);
FORCEPROP 2 LAST $XR10 53 
J 0
(-4449 2514);
DISPLAY 0.638298 (-4449 2514);
PAINT MONO (-4449 2514);
FORCEPROP 2 LAST $XR11 54 
J 0
(-4539 2514);
DISPLAY 0.638298 (-4539 2514);
PAINT MONO (-4539 2514);
FORCEPROP 2 LAST $XR12 77 
J 0
(-4629 2514);
DISPLAY 0.638298 (-4629 2514);
PAINT MONO (-4629 2514);
FORCEPROP 2 LAST $XR13 78 
J 0
(-4719 2514);
DISPLAY 0.638298 (-4719 2514);
PAINT MONO (-4719 2514);
FORCEPROP 2 LAST $XR14 79 
J 0
(-4809 2514);
DISPLAY 0.638298 (-4809 2514);
PAINT MONO (-4809 2514);
FORCEPROP 2 LAST $XR15 80 
J 0
(-4899 2514);
DISPLAY 0.638298 (-4899 2514);
PAINT MONO (-4899 2514);
FORCEPROP 2 LAST $XR16 81 
J 0
(-4989 2514);
DISPLAY 0.638298 (-4989 2514);
PAINT MONO (-4989 2514);
FORCEPROP 2 LAST $XR17 82 
J 0
(-5079 2514);
DISPLAY 0.638298 (-5079 2514);
PAINT MONO (-5079 2514);
FORCEPROP 2 LAST $XR18 83 
J 0
(-5169 2514);
DISPLAY 0.638298 (-5169 2514);
PAINT MONO (-5169 2514);
FORCEPROP 2 LAST $XR19 84 
J 0
(-5259 2514);
DISPLAY 0.638298 (-5259 2514);
PAINT MONO (-5259 2514);
FORCEPROP 2 LAST $XR20 86 
J 0
(-4449 2586);
DISPLAY 0.638298 (-4449 2586);
PAINT MONO (-4449 2586);
FORCEPROP 2 LAST $XR21 87 
J 0
(-4539 2586);
DISPLAY 0.638298 (-4539 2586);
PAINT MONO (-4539 2586);
FORCEPROP 2 LAST $XR22 88 
J 0
(-4629 2586);
DISPLAY 0.638298 (-4629 2586);
PAINT MONO (-4629 2586);
FORCEPROP 2 LAST $XR23 94 
J 0
(-4719 2586);
DISPLAY 0.638298 (-4719 2586);
PAINT MONO (-4719 2586);
FORCEPROP 2 LAST CDS_LIB mstr_standard
J 0
(-4225 2550);
DISPLAY 0.787234 (-4225 2550);
PAINT MONO (-4225 2550);
DISPLAY INVISIBLE (-4225 2550);
FORCEPROP 1 LAST OFFPAGE TRUE
J 0
(-3900 2425);
DISPLAY 1.404255 (-3900 2425);
PAINT GREEN (-3900 2425);
DISPLAY INVISIBLE (-3900 2425);
FORCEPROP 1 LAST COMMENT_BODY TRUE
J 0
(-4125 2475);
DISPLAY 1.404255 (-4125 2475);
PAINT GREEN (-4125 2475);
DISPLAY INVISIBLE (-4125 2475);
FORCEPROP 2 LAST PATH I179
J 0
(-4175 2625);
DISPLAY 0.787234 (-4175 2625);
PAINT ORANGE (-4175 2625);
DISPLAY INVISIBLE (-4175 2625);
FORCEADD GND..1
(-4650 1300);
FORCEPROP 3 LASTPIN (-4650 1350) SIG_NAME GND\g
J 0
(-4640 1360);
DISPLAY 0.659574 (-4640 1360);
PAINT MONO (-4640 1360);
DISPLAY INVISIBLE (-4640 1360);
FORCEPROP 1 LAST VOLTAGE 0
J 0
(-4650 1300);
PAINT SKYBLUE (-4650 1300);
DISPLAY INVISIBLE (-4650 1300);
FORCEPROP 2 LAST BOM_COST MEM
J 0
(-4650 1305);
PAINT ORANGE (-4650 1305);
DISPLAY INVISIBLE (-4650 1305);
FORCEPROP 2 LAST CDS_LIB mstr_symbols
J 0
(-4650 1300);
PAINT ORANGE (-4650 1300);
DISPLAY INVISIBLE (-4650 1300);
FORCEPROP 1 LAST SIZE 1B
J 0
(-4575 1250);
DISPLAY 1.787234 (-4575 1250);
PAINT GREEN (-4575 1250);
DISPLAY INVISIBLE (-4575 1250);
FORCEPROP 1 LAST BODY_TYPE PLUMBING
J 0
(-4695 1257);
DISPLAY 0.340426 (-4695 1257);
PAINT GREEN (-4695 1257);
DISPLAY INVISIBLE (-4695 1257);
FORCEPROP 1 LAST PATH I180
J 0
(-4575 1300);
DISPLAY 1.404255 (-4575 1300);
PAINT GREEN (-4575 1300);
DISPLAY INVISIBLE (-4575 1300);
FORCEPROP 2 LAST ROOM DDR4_CH_D
J 0
(-4650 1305);
PAINT ORANGE (-4650 1305);
DISPLAY INVISIBLE (-4650 1305);
FORCEPROP 1 LAST HDL_POWER GND
J 0
(-4650 1450);
DISPLAY 1.404255 (-4650 1450);
PAINT GREEN (-4650 1450);
DISPLAY INVISIBLE (-4650 1450);
FORCEADD CAP_A..1
R 2
(-4650 1550);
FORCEPROP 1 LAST LOCATION C9L7
J 2
(-4700 1650);
DISPLAY 0.617021 (-4700 1650);
PAINT AQUA (-4700 1650);
FORCEPROP 1 LAST PART_NUMBER A36096-045
J 2
(-4700 1400);
DISPLAY 0.617021 (-4700 1400);
PAINT BLUE (-4700 1400);
FORCEPROP 1 LAST VALUE 0.01UF
J 2
(-4700 1600);
DISPLAY 0.617021 (-4700 1600);
PAINT SKYBLUE (-4700 1600);
FORCEPROP 1 LAST TOLERANCE 10%
J 2
(-4700 1500);
DISPLAY 0.617021 (-4700 1500);
PAINT SKYBLUE (-4700 1500);
FORCEPROP 1 LAST PACK_TYPE 0402V
J 2
(-4700 1350);
DISPLAY 0.617021 (-4700 1350);
PAINT SKYBLUE (-4700 1350);
FORCEPROP 1 LAST VOLTAGE 25V
J 2
(-4700 1550);
DISPLAY 0.617021 (-4700 1550);
PAINT SKYBLUE (-4700 1550);
FORCEPROP 1 LAST MATERIAL X7R
J 2
(-4700 1450);
DISPLAY 0.617021 (-4700 1450);
PAINT SKYBLUE (-4700 1450);
FORCEPROP 2 LAST CDS_LOCATION C9L7
J 2
(-4700 1650);
DISPLAY 0.617021 (-4700 1650);
PAINT AQUA (-4700 1650);
DISPLAY INVISIBLE (-4700 1650);
FORCEPROP 2 LAST BOM_COST MEM
J 0
(-4650 1550);
PAINT ORANGE (-4650 1550);
DISPLAY INVISIBLE (-4650 1550);
FORCEPROP 2 LAST CDS_LIB dev_discrete
J 0
(-4650 1550);
PAINT ORANGE (-4650 1550);
DISPLAY INVISIBLE (-4650 1550);
FORCEPROP 2 LAST CDS_SEC 1
J 2
(-4700 1750);
PAINT MONO (-4700 1750);
DISPLAY INVISIBLE (-4700 1750);
FORCEPROP 2 LAST $SEC 1
J 0
(-4700 1750);
PAINT MONO (-4700 1750);
DISPLAY INVISIBLE (-4700 1750);
FORCEPROP 1 LAST PATH I181
J 2
(-4700 1700);
DISPLAY 0.978723 (-4700 1700);
PAINT WHITE (-4700 1700);
DISPLAY INVISIBLE (-4700 1700);
FORCEPROP 2 LAST ROOM DDR4_CH_L
J 0
(-4650 1550);
PAINT ORANGE (-4650 1550);
DISPLAY INVISIBLE (-4650 1550);
FORCEPROP 1 LASTPIN (-4650 1650) $PN 1
J 2
(-4660 1630);
DISPLAY 0.787234 (-4660 1630);
PAINT ORANGE (-4660 1630);
DISPLAY INVISIBLE (-4660 1630);
FORCEPROP 1 LASTPIN (-4650 1450) $PN 2
J 2
(-4660 1430);
DISPLAY 0.787234 (-4660 1430);
PAINT ORANGE (-4660 1430);
DISPLAY INVISIBLE (-4660 1430);
FORCEADD PVPP_KLM..1
(-950 3075);
FORCEPROP 3 LASTPIN (-950 3025) SIG_NAME PVPP_KLM\g
J 0
(-940 3035);
DISPLAY 0.659574 (-940 3035);
PAINT MONO (-940 3035);
DISPLAY INVISIBLE (-940 3035);
FORCEPROP 1 LAST VOLTAGE 2.5V
J 0
(-995 3032);
DISPLAY 0.340426 (-995 3032);
PAINT SKYBLUE (-995 3032);
DISPLAY INVISIBLE (-995 3032);
FORCEPROP 0 LAST BOM_COST MEM
J 0
(-950 3175);
PAINT ORANGE (-950 3175);
DISPLAY INVISIBLE (-950 3175);
FORCEPROP 2 LAST CDS_LIB mstr_symbols
J 0
(-950 3075);
PAINT ORANGE (-950 3075);
DISPLAY INVISIBLE (-950 3075);
FORCEPROP 1 LAST BODY_TYPE PLUMBING
J 0
(-995 3032);
DISPLAY 0.340426 (-995 3032);
PAINT GREEN (-995 3032);
DISPLAY INVISIBLE (-995 3032);
FORCEPROP 1 LAST PATH I182
J 0
(-900 3100);
DISPLAY 0.872340 (-900 3100);
PAINT AQUA (-900 3100);
DISPLAY INVISIBLE (-900 3100);
FORCEPROP 2 LAST ROOM DDR4_CH_D
J 0
(-950 3175);
PAINT ORANGE (-950 3175);
DISPLAY INVISIBLE (-950 3175);
FORCEPROP 1 LAST HDL_POWER PVPP_KLM
J 1
(-950 3125);
DISPLAY 0.872340 (-950 3125);
PAINT GREEN (-950 3125);
DISPLAY INVISIBLE (-950 3125);
FORCEADD PVPP_KLM..1
(-5150 2250);
FORCEPROP 3 LASTPIN (-5150 2200) SIG_NAME PVPP_KLM\g
J 0
(-5140 2210);
DISPLAY 0.659574 (-5140 2210);
PAINT MONO (-5140 2210);
DISPLAY INVISIBLE (-5140 2210);
FORCEPROP 1 LAST VOLTAGE 2.5V
J 0
(-5195 2207);
DISPLAY 0.340426 (-5195 2207);
PAINT SKYBLUE (-5195 2207);
DISPLAY INVISIBLE (-5195 2207);
FORCEPROP 0 LAST BOM_COST MEM
J 0
(-5150 2350);
PAINT ORANGE (-5150 2350);
DISPLAY INVISIBLE (-5150 2350);
FORCEPROP 2 LAST CDS_LIB mstr_symbols
J 0
(-5150 2250);
PAINT ORANGE (-5150 2250);
DISPLAY INVISIBLE (-5150 2250);
FORCEPROP 1 LAST BODY_TYPE PLUMBING
J 0
(-5195 2207);
DISPLAY 0.340426 (-5195 2207);
PAINT GREEN (-5195 2207);
DISPLAY INVISIBLE (-5195 2207);
FORCEPROP 1 LAST PATH I183
J 0
(-5100 2275);
DISPLAY 0.872340 (-5100 2275);
PAINT AQUA (-5100 2275);
DISPLAY INVISIBLE (-5100 2275);
FORCEPROP 2 LAST ROOM DDR4_CH_M
J 0
(-5150 2350);
PAINT ORANGE (-5150 2350);
DISPLAY INVISIBLE (-5150 2350);
FORCEPROP 1 LAST HDL_POWER PVPP_KLM
J 1
(-5150 2300);
DISPLAY 0.872340 (-5150 2300);
PAINT GREEN (-5150 2300);
DISPLAY INVISIBLE (-5150 2300);
FORCEADD OFFPAGE..1
(-3900 1450);
FORCEPROP 2 LAST $XR0 89 
J 0
(-4121 1450);
DISPLAY 0.638298 (-4121 1450);
PAINT MONO (-4121 1450);
FORCEPROP 2 LAST $XR1 83 
J 0
(-4211 1450);
DISPLAY 0.638298 (-4211 1450);
PAINT MONO (-4211 1450);
FORCEPROP 2 LAST $XR2 84 
J 0
(-4301 1450);
DISPLAY 0.638298 (-4301 1450);
PAINT MONO (-4301 1450);
FORCEPROP 2 LAST $XR3 86 
J 0
(-4391 1450);
DISPLAY 0.638298 (-4391 1450);
PAINT MONO (-4391 1450);
FORCEPROP 2 LAST $XR4 87 
J 0
(-4481 1450);
DISPLAY 0.638298 (-4481 1450);
PAINT MONO (-4481 1450);
FORCEPROP 2 LAST $XR5 88 
J 0
(-4571 1450);
DISPLAY 0.638298 (-4571 1450);
PAINT MONO (-4571 1450);
FORCEPROP 2 LAST CDS_LIB mstr_standard
J 0
(-3900 1450);
PAINT ORANGE (-3900 1450);
DISPLAY INVISIBLE (-3900 1450);
FORCEPROP 1 LAST OFFPAGE TRUE
J 0
(-3575 1325);
DISPLAY 0.936170 (-3575 1325);
PAINT GREEN (-3575 1325);
DISPLAY INVISIBLE (-3575 1325);
FORCEPROP 1 LAST COMMENT_BODY TRUE
J 0
(-3775 1350);
DISPLAY 0.936170 (-3775 1350);
PAINT GREEN (-3775 1350);
DISPLAY INVISIBLE (-3775 1350);
FORCEPROP 2 LAST PATH I184
J 0
(-3850 1525);
PAINT ORANGE (-3850 1525);
DISPLAY INVISIBLE (-3850 1525);
FORCEADD P12V_NVDIMM_KLM..1
(375 3025);
FORCEPROP 3 LASTPIN (375 2975) SIG_NAME P12V_NVDIMM_KLM\g
J 0
(385 2985);
DISPLAY 0.659574 (385 2985);
PAINT MONO (385 2985);
DISPLAY INVISIBLE (385 2985);
FORCEPROP 1 LAST VOLTAGE 12.0
J 0
(330 2982);
DISPLAY 0.340426 (330 2982);
PAINT SKYBLUE (330 2982);
DISPLAY INVISIBLE (330 2982);
FORCEPROP 2 LAST CDS_LIB mstr_symbols
J 0
(375 3025);
PAINT ORANGE (375 3025);
DISPLAY INVISIBLE (375 3025);
FORCEPROP 1 LAST BODY_TYPE PLUMBING
J 0
(330 2982);
DISPLAY 0.340426 (330 2982);
PAINT GREEN (330 2982);
DISPLAY INVISIBLE (330 2982);
FORCEPROP 1 LAST PATH I185
J 0
(425 3050);
DISPLAY 0.872340 (425 3050);
PAINT AQUA (425 3050);
DISPLAY INVISIBLE (425 3050);
FORCEPROP 1 LAST HDL_POWER P12V_NVDIMM_KLM
J 1
(375 3075);
DISPLAY 0.872340 (375 3075);
PAINT GREEN (375 3075);
DISPLAY INVISIBLE (375 3075);
FORCEADD TAP..6
R 2
(900 4500);
FORCEPROP 3 LASTPIN (850 4500) SIG_NAME M_L_DQS_DN<11>
J 0
(860 4510);
DISPLAY 0.659574 (860 4510);
PAINT MONO (860 4510);
DISPLAY INVISIBLE (860 4510);
FORCEPROP 1 LASTPIN (850 4500) BN 11
J 2
(900 4510);
DISPLAY 0.617021 (900 4510);
PAINT PINK (900 4510);
FORCEPROP 2 LAST CDS_LIB mstr_standard
J 0
(900 4500);
DISPLAY 0.787234 (900 4500);
PAINT MONO (900 4500);
DISPLAY INVISIBLE (900 4500);
FORCEPROP 1 LAST BODY_TYPE PLUMBING
J 2
(900 4450);
DISPLAY 1.234043 (900 4450);
PAINT GREEN (900 4450);
DISPLAY INVISIBLE (900 4450);
FORCEPROP 1 LAST HDL_TAP TRUE
J 2
(575 4375);
DISPLAY 1.234043 (575 4375);
PAINT GREEN (575 4375);
DISPLAY INVISIBLE (575 4375);
FORCEPROP 1 LAST PATH I19
J 2
(900 4500);
DISPLAY 0.936170 (900 4500);
PAINT GREEN (900 4500);
DISPLAY INVISIBLE (900 4500);
FORCEADD OFFPAGE..3
(1600 5150);
FORCEPROP 2 LAST $XR0 61 
J 0
(1814 5150);
DISPLAY 0.638298 (1814 5150);
PAINT MONO (1814 5150);
FORCEPROP 2 LAST $XR1 86 
J 0
(1904 5150);
DISPLAY 0.638298 (1904 5150);
PAINT MONO (1904 5150);
FORCEPROP 2 LAST CDS_LIB mstr_standard
J 0
(1600 5150);
DISPLAY 0.787234 (1600 5150);
PAINT MONO (1600 5150);
DISPLAY INVISIBLE (1600 5150);
FORCEPROP 1 LAST OFFPAGE TRUE
J 0
(1925 5025);
DISPLAY 0.936170 (1925 5025);
PAINT GREEN (1925 5025);
DISPLAY INVISIBLE (1925 5025);
FORCEPROP 1 LAST COMMENT_BODY TRUE
J 0
(1550 5050);
DISPLAY 0.936170 (1550 5050);
PAINT GREEN (1550 5050);
DISPLAY INVISIBLE (1550 5050);
FORCEPROP 2 LAST PATH I2
J 0
(1800 5225);
DISPLAY 0.787234 (1800 5225);
PAINT MONO (1800 5225);
DISPLAY INVISIBLE (1800 5225);
FORCEADD TAP..6
R 2
(900 4400);
FORCEPROP 3 LASTPIN (850 4400) SIG_NAME M_L_DQS_DN<10>
J 0
(860 4410);
DISPLAY 0.659574 (860 4410);
PAINT MONO (860 4410);
DISPLAY INVISIBLE (860 4410);
FORCEPROP 1 LASTPIN (850 4400) BN 10
J 2
(900 4410);
DISPLAY 0.617021 (900 4410);
PAINT PINK (900 4410);
FORCEPROP 2 LAST CDS_LIB mstr_standard
J 0
(900 4400);
DISPLAY 0.787234 (900 4400);
PAINT MONO (900 4400);
DISPLAY INVISIBLE (900 4400);
FORCEPROP 1 LAST BODY_TYPE PLUMBING
J 2
(900 4350);
DISPLAY 1.234043 (900 4350);
PAINT GREEN (900 4350);
DISPLAY INVISIBLE (900 4350);
FORCEPROP 1 LAST HDL_TAP TRUE
J 2
(575 4275);
DISPLAY 1.234043 (575 4275);
PAINT GREEN (575 4275);
DISPLAY INVISIBLE (575 4275);
FORCEPROP 1 LAST PATH I20
J 2
(900 4400);
DISPLAY 0.936170 (900 4400);
PAINT GREEN (900 4400);
DISPLAY INVISIBLE (900 4400);
FORCEADD TAP..6
R 2
(900 4300);
FORCEPROP 3 LASTPIN (850 4300) SIG_NAME M_L_DQS_DN<9>
J 0
(860 4310);
DISPLAY 0.659574 (860 4310);
PAINT MONO (860 4310);
DISPLAY INVISIBLE (860 4310);
FORCEPROP 1 LASTPIN (850 4300) BN 9
J 2
(900 4310);
DISPLAY 0.617021 (900 4310);
PAINT PINK (900 4310);
FORCEPROP 2 LAST CDS_LIB mstr_standard
J 0
(900 4300);
DISPLAY 0.787234 (900 4300);
PAINT MONO (900 4300);
DISPLAY INVISIBLE (900 4300);
FORCEPROP 1 LAST BODY_TYPE PLUMBING
J 2
(900 4250);
DISPLAY 1.234043 (900 4250);
PAINT GREEN (900 4250);
DISPLAY INVISIBLE (900 4250);
FORCEPROP 1 LAST HDL_TAP TRUE
J 2
(575 4175);
DISPLAY 1.234043 (575 4175);
PAINT GREEN (575 4175);
DISPLAY INVISIBLE (575 4175);
FORCEPROP 1 LAST PATH I21
J 2
(900 4300);
DISPLAY 0.936170 (900 4300);
PAINT GREEN (900 4300);
DISPLAY INVISIBLE (900 4300);
FORCEADD TAP..6
R 2
(900 4200);
FORCEPROP 3 LASTPIN (850 4200) SIG_NAME M_L_DQS_DN<8>
J 0
(860 4210);
DISPLAY 0.659574 (860 4210);
PAINT MONO (860 4210);
DISPLAY INVISIBLE (860 4210);
FORCEPROP 1 LASTPIN (850 4200) BN 8
J 2
(900 4210);
DISPLAY 0.617021 (900 4210);
PAINT PINK (900 4210);
FORCEPROP 2 LAST CDS_LIB mstr_standard
J 0
(900 4200);
DISPLAY 0.787234 (900 4200);
PAINT MONO (900 4200);
DISPLAY INVISIBLE (900 4200);
FORCEPROP 1 LAST BODY_TYPE PLUMBING
J 2
(900 4150);
DISPLAY 1.234043 (900 4150);
PAINT GREEN (900 4150);
DISPLAY INVISIBLE (900 4150);
FORCEPROP 1 LAST HDL_TAP TRUE
J 2
(575 4075);
DISPLAY 1.234043 (575 4075);
PAINT GREEN (575 4075);
DISPLAY INVISIBLE (575 4075);
FORCEPROP 1 LAST PATH I22
J 2
(900 4200);
DISPLAY 0.936170 (900 4200);
PAINT GREEN (900 4200);
DISPLAY INVISIBLE (900 4200);
FORCEADD TAP..6
R 2
(900 4100);
FORCEPROP 3 LASTPIN (850 4100) SIG_NAME M_L_DQS_DN<7>
J 0
(860 4110);
DISPLAY 0.659574 (860 4110);
PAINT MONO (860 4110);
DISPLAY INVISIBLE (860 4110);
FORCEPROP 1 LASTPIN (850 4100) BN 7
J 2
(900 4110);
DISPLAY 0.617021 (900 4110);
PAINT PINK (900 4110);
FORCEPROP 2 LAST CDS_LIB mstr_standard
J 0
(900 4100);
DISPLAY 0.787234 (900 4100);
PAINT MONO (900 4100);
DISPLAY INVISIBLE (900 4100);
FORCEPROP 1 LAST BODY_TYPE PLUMBING
J 2
(900 4050);
DISPLAY 1.234043 (900 4050);
PAINT GREEN (900 4050);
DISPLAY INVISIBLE (900 4050);
FORCEPROP 1 LAST HDL_TAP TRUE
J 2
(575 3975);
DISPLAY 1.234043 (575 3975);
PAINT GREEN (575 3975);
DISPLAY INVISIBLE (575 3975);
FORCEPROP 1 LAST PATH I23
J 2
(900 4100);
DISPLAY 0.936170 (900 4100);
PAINT GREEN (900 4100);
DISPLAY INVISIBLE (900 4100);
FORCEADD TAP..6
R 2
(700 4450);
FORCEPROP 3 LASTPIN (650 4450) SIG_NAME M_L_DQS_DP<10>
J 0
(660 4460);
DISPLAY 0.659574 (660 4460);
PAINT MONO (660 4460);
DISPLAY INVISIBLE (660 4460);
FORCEPROP 1 LASTPIN (650 4450) BN 10
J 2
(700 4460);
DISPLAY 0.617021 (700 4460);
PAINT PINK (700 4460);
FORCEPROP 2 LAST CDS_LIB mstr_standard
J 0
(700 4450);
DISPLAY 0.787234 (700 4450);
PAINT MONO (700 4450);
DISPLAY INVISIBLE (700 4450);
FORCEPROP 1 LAST BODY_TYPE PLUMBING
J 2
(700 4400);
DISPLAY 1.234043 (700 4400);
PAINT GREEN (700 4400);
DISPLAY INVISIBLE (700 4400);
FORCEPROP 1 LAST HDL_TAP TRUE
J 2
(375 4325);
DISPLAY 1.234043 (375 4325);
PAINT GREEN (375 4325);
DISPLAY INVISIBLE (375 4325);
FORCEPROP 1 LAST PATH I24
J 2
(700 4450);
DISPLAY 0.936170 (700 4450);
PAINT GREEN (700 4450);
DISPLAY INVISIBLE (700 4450);
FORCEADD TAP..6
R 2
(700 4350);
FORCEPROP 3 LASTPIN (650 4350) SIG_NAME M_L_DQS_DP<9>
J 0
(660 4360);
DISPLAY 0.659574 (660 4360);
PAINT MONO (660 4360);
DISPLAY INVISIBLE (660 4360);
FORCEPROP 1 LASTPIN (650 4350) BN 9
J 2
(700 4360);
DISPLAY 0.617021 (700 4360);
PAINT PINK (700 4360);
FORCEPROP 2 LAST CDS_LIB mstr_standard
J 0
(700 4350);
DISPLAY 0.787234 (700 4350);
PAINT MONO (700 4350);
DISPLAY INVISIBLE (700 4350);
FORCEPROP 1 LAST BODY_TYPE PLUMBING
J 2
(700 4300);
DISPLAY 1.234043 (700 4300);
PAINT GREEN (700 4300);
DISPLAY INVISIBLE (700 4300);
FORCEPROP 1 LAST HDL_TAP TRUE
J 2
(375 4225);
DISPLAY 1.234043 (375 4225);
PAINT GREEN (375 4225);
DISPLAY INVISIBLE (375 4225);
FORCEPROP 1 LAST PATH I25
J 2
(700 4350);
DISPLAY 0.936170 (700 4350);
PAINT GREEN (700 4350);
DISPLAY INVISIBLE (700 4350);
FORCEADD TAP..6
R 2
(700 4050);
FORCEPROP 3 LASTPIN (650 4050) SIG_NAME M_L_DQS_DP<6>
J 0
(660 4060);
DISPLAY 0.659574 (660 4060);
PAINT MONO (660 4060);
DISPLAY INVISIBLE (660 4060);
FORCEPROP 1 LASTPIN (650 4050) BN 6
J 2
(700 4060);
DISPLAY 0.617021 (700 4060);
PAINT PINK (700 4060);
FORCEPROP 2 LAST CDS_LIB mstr_standard
J 0
(700 4050);
DISPLAY 0.787234 (700 4050);
PAINT MONO (700 4050);
DISPLAY INVISIBLE (700 4050);
FORCEPROP 1 LAST BODY_TYPE PLUMBING
J 2
(700 4000);
DISPLAY 1.234043 (700 4000);
PAINT GREEN (700 4000);
DISPLAY INVISIBLE (700 4000);
FORCEPROP 1 LAST HDL_TAP TRUE
J 2
(375 3925);
DISPLAY 1.234043 (375 3925);
PAINT GREEN (375 3925);
DISPLAY INVISIBLE (375 3925);
FORCEPROP 1 LAST PATH I26
J 2
(700 4050);
DISPLAY 0.936170 (700 4050);
PAINT GREEN (700 4050);
DISPLAY INVISIBLE (700 4050);
FORCEADD TAP..6
R 2
(700 4150);
FORCEPROP 3 LASTPIN (650 4150) SIG_NAME M_L_DQS_DP<7>
J 0
(660 4160);
DISPLAY 0.659574 (660 4160);
PAINT MONO (660 4160);
DISPLAY INVISIBLE (660 4160);
FORCEPROP 1 LASTPIN (650 4150) BN 7
J 2
(700 4160);
DISPLAY 0.617021 (700 4160);
PAINT PINK (700 4160);
FORCEPROP 2 LAST CDS_LIB mstr_standard
J 0
(700 4150);
DISPLAY 0.787234 (700 4150);
PAINT MONO (700 4150);
DISPLAY INVISIBLE (700 4150);
FORCEPROP 1 LAST BODY_TYPE PLUMBING
J 2
(700 4100);
DISPLAY 1.234043 (700 4100);
PAINT GREEN (700 4100);
DISPLAY INVISIBLE (700 4100);
FORCEPROP 1 LAST HDL_TAP TRUE
J 2
(375 4025);
DISPLAY 1.234043 (375 4025);
PAINT GREEN (375 4025);
DISPLAY INVISIBLE (375 4025);
FORCEPROP 1 LAST PATH I27
J 2
(700 4150);
DISPLAY 0.936170 (700 4150);
PAINT GREEN (700 4150);
DISPLAY INVISIBLE (700 4150);
FORCEADD TAP..6
R 2
(700 4250);
FORCEPROP 3 LASTPIN (650 4250) SIG_NAME M_L_DQS_DP<8>
J 0
(660 4260);
DISPLAY 0.659574 (660 4260);
PAINT MONO (660 4260);
DISPLAY INVISIBLE (660 4260);
FORCEPROP 1 LASTPIN (650 4250) BN 8
J 2
(700 4260);
DISPLAY 0.617021 (700 4260);
PAINT PINK (700 4260);
FORCEPROP 2 LAST CDS_LIB mstr_standard
J 0
(700 4250);
DISPLAY 0.787234 (700 4250);
PAINT MONO (700 4250);
DISPLAY INVISIBLE (700 4250);
FORCEPROP 1 LAST BODY_TYPE PLUMBING
J 2
(700 4200);
DISPLAY 1.234043 (700 4200);
PAINT GREEN (700 4200);
DISPLAY INVISIBLE (700 4200);
FORCEPROP 1 LAST HDL_TAP TRUE
J 2
(375 4125);
DISPLAY 1.234043 (375 4125);
PAINT GREEN (375 4125);
DISPLAY INVISIBLE (375 4125);
FORCEPROP 1 LAST PATH I28
J 2
(700 4250);
DISPLAY 0.936170 (700 4250);
PAINT GREEN (700 4250);
DISPLAY INVISIBLE (700 4250);
FORCEADD TAP..6
R 2
(900 4000);
FORCEPROP 3 LASTPIN (850 4000) SIG_NAME M_L_DQS_DN<6>
J 0
(860 4010);
DISPLAY 0.659574 (860 4010);
PAINT MONO (860 4010);
DISPLAY INVISIBLE (860 4010);
FORCEPROP 1 LASTPIN (850 4000) BN 6
J 2
(900 4010);
DISPLAY 0.617021 (900 4010);
PAINT PINK (900 4010);
FORCEPROP 2 LAST CDS_LIB mstr_standard
J 0
(900 4000);
DISPLAY 0.787234 (900 4000);
PAINT MONO (900 4000);
DISPLAY INVISIBLE (900 4000);
FORCEPROP 1 LAST BODY_TYPE PLUMBING
J 2
(900 3950);
DISPLAY 1.234043 (900 3950);
PAINT GREEN (900 3950);
DISPLAY INVISIBLE (900 3950);
FORCEPROP 1 LAST HDL_TAP TRUE
J 2
(575 3875);
DISPLAY 1.234043 (575 3875);
PAINT GREEN (575 3875);
DISPLAY INVISIBLE (575 3875);
FORCEPROP 1 LAST PATH I29
J 2
(900 4000);
DISPLAY 0.936170 (900 4000);
PAINT GREEN (900 4000);
DISPLAY INVISIBLE (900 4000);
FORCEADD TAP..6
R 2
(900 5100);
FORCEPROP 3 LASTPIN (850 5100) SIG_NAME M_L_DQS_DN<17>
J 0
(860 5110);
DISPLAY 0.659574 (860 5110);
PAINT MONO (860 5110);
DISPLAY INVISIBLE (860 5110);
FORCEPROP 1 LASTPIN (850 5100) BN 17
J 2
(900 5110);
DISPLAY 0.617021 (900 5110);
PAINT PINK (900 5110);
FORCEPROP 2 LAST CDS_LIB mstr_standard
J 2
(900 5100);
DISPLAY 0.787234 (900 5100);
PAINT MONO (900 5100);
DISPLAY INVISIBLE (900 5100);
FORCEPROP 1 LAST BODY_TYPE PLUMBING
J 2
(900 5050);
DISPLAY 1.234043 (900 5050);
PAINT GREEN (900 5050);
DISPLAY INVISIBLE (900 5050);
FORCEPROP 1 LAST HDL_TAP TRUE
J 2
(575 4975);
DISPLAY 1.234043 (575 4975);
PAINT GREEN (575 4975);
DISPLAY INVISIBLE (575 4975);
FORCEPROP 1 LAST PATH I3
J 2
(900 5100);
DISPLAY 0.936170 (900 5100);
PAINT GREEN (900 5100);
DISPLAY INVISIBLE (900 5100);
FORCEADD TAP..6
R 2
(900 3900);
FORCEPROP 3 LASTPIN (850 3900) SIG_NAME M_L_DQS_DN<5>
J 0
(860 3910);
DISPLAY 0.659574 (860 3910);
PAINT MONO (860 3910);
DISPLAY INVISIBLE (860 3910);
FORCEPROP 1 LASTPIN (850 3900) BN 5
J 2
(900 3910);
DISPLAY 0.617021 (900 3910);
PAINT PINK (900 3910);
FORCEPROP 2 LAST CDS_LIB mstr_standard
J 0
(900 3900);
DISPLAY 0.787234 (900 3900);
PAINT MONO (900 3900);
DISPLAY INVISIBLE (900 3900);
FORCEPROP 1 LAST BODY_TYPE PLUMBING
J 2
(900 3850);
DISPLAY 1.234043 (900 3850);
PAINT GREEN (900 3850);
DISPLAY INVISIBLE (900 3850);
FORCEPROP 1 LAST HDL_TAP TRUE
J 2
(575 3775);
DISPLAY 1.234043 (575 3775);
PAINT GREEN (575 3775);
DISPLAY INVISIBLE (575 3775);
FORCEPROP 1 LAST PATH I30
J 2
(900 3900);
DISPLAY 0.936170 (900 3900);
PAINT GREEN (900 3900);
DISPLAY INVISIBLE (900 3900);
FORCEADD TAP..6
R 2
(900 3800);
FORCEPROP 3 LASTPIN (850 3800) SIG_NAME M_L_DQS_DN<4>
J 0
(860 3810);
DISPLAY 0.659574 (860 3810);
PAINT MONO (860 3810);
DISPLAY INVISIBLE (860 3810);
FORCEPROP 1 LASTPIN (850 3800) BN 4
J 2
(900 3810);
DISPLAY 0.617021 (900 3810);
PAINT PINK (900 3810);
FORCEPROP 2 LAST CDS_LIB mstr_standard
J 0
(900 3800);
DISPLAY 0.787234 (900 3800);
PAINT MONO (900 3800);
DISPLAY INVISIBLE (900 3800);
FORCEPROP 1 LAST BODY_TYPE PLUMBING
J 2
(900 3750);
DISPLAY 1.234043 (900 3750);
PAINT GREEN (900 3750);
DISPLAY INVISIBLE (900 3750);
FORCEPROP 1 LAST HDL_TAP TRUE
J 2
(575 3675);
DISPLAY 1.234043 (575 3675);
PAINT GREEN (575 3675);
DISPLAY INVISIBLE (575 3675);
FORCEPROP 1 LAST PATH I31
J 2
(900 3800);
DISPLAY 0.936170 (900 3800);
PAINT GREEN (900 3800);
DISPLAY INVISIBLE (900 3800);
FORCEADD TAP..6
R 2
(900 3700);
FORCEPROP 3 LASTPIN (850 3700) SIG_NAME M_L_DQS_DN<3>
J 0
(860 3710);
DISPLAY 0.659574 (860 3710);
PAINT MONO (860 3710);
DISPLAY INVISIBLE (860 3710);
FORCEPROP 1 LASTPIN (850 3700) BN 3
J 2
(900 3710);
DISPLAY 0.617021 (900 3710);
PAINT PINK (900 3710);
FORCEPROP 2 LAST CDS_LIB mstr_standard
J 0
(900 3700);
DISPLAY 0.787234 (900 3700);
PAINT MONO (900 3700);
DISPLAY INVISIBLE (900 3700);
FORCEPROP 1 LAST BODY_TYPE PLUMBING
J 2
(900 3650);
DISPLAY 1.234043 (900 3650);
PAINT GREEN (900 3650);
DISPLAY INVISIBLE (900 3650);
FORCEPROP 1 LAST HDL_TAP TRUE
J 2
(575 3575);
DISPLAY 1.234043 (575 3575);
PAINT GREEN (575 3575);
DISPLAY INVISIBLE (575 3575);
FORCEPROP 1 LAST PATH I32
J 2
(900 3700);
DISPLAY 0.936170 (900 3700);
PAINT GREEN (900 3700);
DISPLAY INVISIBLE (900 3700);
FORCEADD TAP..6
R 2
(900 3600);
FORCEPROP 3 LASTPIN (850 3600) SIG_NAME M_L_DQS_DN<2>
J 0
(860 3610);
DISPLAY 0.659574 (860 3610);
PAINT MONO (860 3610);
DISPLAY INVISIBLE (860 3610);
FORCEPROP 1 LASTPIN (850 3600) BN 2
J 2
(900 3610);
DISPLAY 0.617021 (900 3610);
PAINT PINK (900 3610);
FORCEPROP 2 LAST CDS_LIB mstr_standard
J 0
(900 3600);
DISPLAY 0.787234 (900 3600);
PAINT MONO (900 3600);
DISPLAY INVISIBLE (900 3600);
FORCEPROP 1 LAST BODY_TYPE PLUMBING
J 2
(900 3550);
DISPLAY 1.234043 (900 3550);
PAINT GREEN (900 3550);
DISPLAY INVISIBLE (900 3550);
FORCEPROP 1 LAST HDL_TAP TRUE
J 2
(575 3475);
DISPLAY 1.234043 (575 3475);
PAINT GREEN (575 3475);
DISPLAY INVISIBLE (575 3475);
FORCEPROP 1 LAST PATH I33
J 2
(900 3600);
DISPLAY 0.936170 (900 3600);
PAINT GREEN (900 3600);
DISPLAY INVISIBLE (900 3600);
FORCEADD TAP..6
R 2
(700 3950);
FORCEPROP 3 LASTPIN (650 3950) SIG_NAME M_L_DQS_DP<5>
J 0
(660 3960);
DISPLAY 0.659574 (660 3960);
PAINT MONO (660 3960);
DISPLAY INVISIBLE (660 3960);
FORCEPROP 1 LASTPIN (650 3950) BN 5
J 2
(700 3960);
DISPLAY 0.617021 (700 3960);
PAINT PINK (700 3960);
FORCEPROP 2 LAST CDS_LIB mstr_standard
J 0
(700 3950);
DISPLAY 0.787234 (700 3950);
PAINT MONO (700 3950);
DISPLAY INVISIBLE (700 3950);
FORCEPROP 1 LAST BODY_TYPE PLUMBING
J 2
(700 3900);
DISPLAY 1.234043 (700 3900);
PAINT GREEN (700 3900);
DISPLAY INVISIBLE (700 3900);
FORCEPROP 1 LAST HDL_TAP TRUE
J 2
(375 3825);
DISPLAY 1.234043 (375 3825);
PAINT GREEN (375 3825);
DISPLAY INVISIBLE (375 3825);
FORCEPROP 1 LAST PATH I34
J 2
(700 3950);
DISPLAY 0.936170 (700 3950);
PAINT GREEN (700 3950);
DISPLAY INVISIBLE (700 3950);
FORCEADD TAP..6
R 2
(700 3850);
FORCEPROP 3 LASTPIN (650 3850) SIG_NAME M_L_DQS_DP<4>
J 0
(660 3860);
DISPLAY 0.659574 (660 3860);
PAINT MONO (660 3860);
DISPLAY INVISIBLE (660 3860);
FORCEPROP 1 LASTPIN (650 3850) BN 4
J 2
(700 3860);
DISPLAY 0.617021 (700 3860);
PAINT PINK (700 3860);
FORCEPROP 2 LAST CDS_LIB mstr_standard
J 0
(700 3850);
DISPLAY 0.787234 (700 3850);
PAINT MONO (700 3850);
DISPLAY INVISIBLE (700 3850);
FORCEPROP 1 LAST BODY_TYPE PLUMBING
J 2
(700 3800);
DISPLAY 1.234043 (700 3800);
PAINT GREEN (700 3800);
DISPLAY INVISIBLE (700 3800);
FORCEPROP 1 LAST HDL_TAP TRUE
J 2
(375 3725);
DISPLAY 1.234043 (375 3725);
PAINT GREEN (375 3725);
DISPLAY INVISIBLE (375 3725);
FORCEPROP 1 LAST PATH I35
J 2
(700 3850);
DISPLAY 0.936170 (700 3850);
PAINT GREEN (700 3850);
DISPLAY INVISIBLE (700 3850);
FORCEADD TAP..6
R 2
(700 3650);
FORCEPROP 3 LASTPIN (650 3650) SIG_NAME M_L_DQS_DP<2>
J 0
(660 3660);
DISPLAY 0.659574 (660 3660);
PAINT MONO (660 3660);
DISPLAY INVISIBLE (660 3660);
FORCEPROP 1 LASTPIN (650 3650) BN 2
J 2
(700 3660);
DISPLAY 0.617021 (700 3660);
PAINT PINK (700 3660);
FORCEPROP 2 LAST CDS_LIB mstr_standard
J 0
(700 3650);
DISPLAY 0.787234 (700 3650);
PAINT MONO (700 3650);
DISPLAY INVISIBLE (700 3650);
FORCEPROP 1 LAST BODY_TYPE PLUMBING
J 2
(700 3600);
DISPLAY 1.234043 (700 3600);
PAINT GREEN (700 3600);
DISPLAY INVISIBLE (700 3600);
FORCEPROP 1 LAST HDL_TAP TRUE
J 2
(375 3525);
DISPLAY 1.234043 (375 3525);
PAINT GREEN (375 3525);
DISPLAY INVISIBLE (375 3525);
FORCEPROP 1 LAST PATH I36
J 2
(700 3650);
DISPLAY 0.936170 (700 3650);
PAINT GREEN (700 3650);
DISPLAY INVISIBLE (700 3650);
FORCEADD TAP..6
R 2
(700 3550);
FORCEPROP 3 LASTPIN (650 3550) SIG_NAME M_L_DQS_DP<1>
J 0
(660 3560);
DISPLAY 0.659574 (660 3560);
PAINT MONO (660 3560);
DISPLAY INVISIBLE (660 3560);
FORCEPROP 1 LASTPIN (650 3550) BN 1
J 2
(700 3560);
DISPLAY 0.617021 (700 3560);
PAINT PINK (700 3560);
FORCEPROP 2 LAST CDS_LIB mstr_standard
J 0
(700 3550);
DISPLAY 0.787234 (700 3550);
PAINT MONO (700 3550);
DISPLAY INVISIBLE (700 3550);
FORCEPROP 1 LAST BODY_TYPE PLUMBING
J 2
(700 3500);
DISPLAY 1.234043 (700 3500);
PAINT GREEN (700 3500);
DISPLAY INVISIBLE (700 3500);
FORCEPROP 1 LAST HDL_TAP TRUE
J 2
(375 3425);
DISPLAY 1.234043 (375 3425);
PAINT GREEN (375 3425);
DISPLAY INVISIBLE (375 3425);
FORCEPROP 1 LAST PATH I37
J 2
(700 3550);
DISPLAY 0.936170 (700 3550);
PAINT GREEN (700 3550);
DISPLAY INVISIBLE (700 3550);
FORCEADD TAP..6
R 2
(700 3750);
FORCEPROP 3 LASTPIN (650 3750) SIG_NAME M_L_DQS_DP<3>
J 0
(660 3760);
DISPLAY 0.659574 (660 3760);
PAINT MONO (660 3760);
DISPLAY INVISIBLE (660 3760);
FORCEPROP 1 LASTPIN (650 3750) BN 3
J 2
(700 3760);
DISPLAY 0.617021 (700 3760);
PAINT PINK (700 3760);
FORCEPROP 2 LAST CDS_LIB mstr_standard
J 0
(700 3750);
DISPLAY 0.787234 (700 3750);
PAINT MONO (700 3750);
DISPLAY INVISIBLE (700 3750);
FORCEPROP 1 LAST BODY_TYPE PLUMBING
J 2
(700 3700);
DISPLAY 1.234043 (700 3700);
PAINT GREEN (700 3700);
DISPLAY INVISIBLE (700 3700);
FORCEPROP 1 LAST HDL_TAP TRUE
J 2
(375 3625);
DISPLAY 1.234043 (375 3625);
PAINT GREEN (375 3625);
DISPLAY INVISIBLE (375 3625);
FORCEPROP 1 LAST PATH I38
J 2
(700 3750);
DISPLAY 0.936170 (700 3750);
PAINT GREEN (700 3750);
DISPLAY INVISIBLE (700 3750);
FORCEADD TAP..6
R 2
(900 3400);
FORCEPROP 3 LASTPIN (850 3400) SIG_NAME M_L_DQS_DN<0>
J 0
(860 3410);
DISPLAY 0.659574 (860 3410);
PAINT MONO (860 3410);
DISPLAY INVISIBLE (860 3410);
FORCEPROP 1 LASTPIN (850 3400) BN 0
J 2
(900 3410);
DISPLAY 0.617021 (900 3410);
PAINT PINK (900 3410);
FORCEPROP 2 LAST CDS_LIB mstr_standard
J 0
(900 3400);
DISPLAY 0.787234 (900 3400);
PAINT MONO (900 3400);
DISPLAY INVISIBLE (900 3400);
FORCEPROP 1 LAST BODY_TYPE PLUMBING
J 2
(900 3350);
DISPLAY 1.234043 (900 3350);
PAINT GREEN (900 3350);
DISPLAY INVISIBLE (900 3350);
FORCEPROP 1 LAST HDL_TAP TRUE
J 2
(575 3275);
DISPLAY 1.234043 (575 3275);
PAINT GREEN (575 3275);
DISPLAY INVISIBLE (575 3275);
FORCEPROP 1 LAST PATH I39
J 2
(900 3400);
DISPLAY 0.936170 (900 3400);
PAINT GREEN (900 3400);
DISPLAY INVISIBLE (900 3400);
FORCEADD TAP..6
R 2
(700 5150);
FORCEPROP 3 LASTPIN (650 5150) SIG_NAME M_L_DQS_DP<17>
J 0
(660 5160);
DISPLAY 0.659574 (660 5160);
PAINT MONO (660 5160);
DISPLAY INVISIBLE (660 5160);
FORCEPROP 1 LASTPIN (650 5150) BN 17
J 2
(700 5160);
DISPLAY 0.617021 (700 5160);
PAINT PINK (700 5160);
FORCEPROP 2 LAST CDS_LIB mstr_standard
J 2
(700 5150);
DISPLAY 0.787234 (700 5150);
PAINT MONO (700 5150);
DISPLAY INVISIBLE (700 5150);
FORCEPROP 1 LAST BODY_TYPE PLUMBING
J 2
(700 5100);
DISPLAY 1.234043 (700 5100);
PAINT GREEN (700 5100);
DISPLAY INVISIBLE (700 5100);
FORCEPROP 1 LAST HDL_TAP TRUE
J 2
(375 5025);
DISPLAY 1.234043 (375 5025);
PAINT GREEN (375 5025);
DISPLAY INVISIBLE (375 5025);
FORCEPROP 1 LAST PATH I4
J 2
(700 5150);
DISPLAY 0.936170 (700 5150);
PAINT GREEN (700 5150);
DISPLAY INVISIBLE (700 5150);
FORCEADD TAP..6
R 2
(900 3500);
FORCEPROP 3 LASTPIN (850 3500) SIG_NAME M_L_DQS_DN<1>
J 0
(860 3510);
DISPLAY 0.659574 (860 3510);
PAINT MONO (860 3510);
DISPLAY INVISIBLE (860 3510);
FORCEPROP 1 LASTPIN (850 3500) BN 1
J 2
(900 3510);
DISPLAY 0.617021 (900 3510);
PAINT PINK (900 3510);
FORCEPROP 2 LAST CDS_LIB mstr_standard
J 0
(900 3500);
DISPLAY 0.787234 (900 3500);
PAINT MONO (900 3500);
DISPLAY INVISIBLE (900 3500);
FORCEPROP 1 LAST BODY_TYPE PLUMBING
J 2
(900 3450);
DISPLAY 1.234043 (900 3450);
PAINT GREEN (900 3450);
DISPLAY INVISIBLE (900 3450);
FORCEPROP 1 LAST HDL_TAP TRUE
J 2
(575 3375);
DISPLAY 1.234043 (575 3375);
PAINT GREEN (575 3375);
DISPLAY INVISIBLE (575 3375);
FORCEPROP 1 LAST PATH I40
J 2
(900 3500);
DISPLAY 0.936170 (900 3500);
PAINT GREEN (900 3500);
DISPLAY INVISIBLE (900 3500);
FORCEADD TAP..6
R 2
(700 3450);
FORCEPROP 3 LASTPIN (650 3450) SIG_NAME M_L_DQS_DP<0>
J 0
(660 3460);
DISPLAY 0.659574 (660 3460);
PAINT MONO (660 3460);
DISPLAY INVISIBLE (660 3460);
FORCEPROP 1 LASTPIN (650 3450) BN 0
J 2
(700 3460);
DISPLAY 0.617021 (700 3460);
PAINT PINK (700 3460);
FORCEPROP 2 LAST CDS_LIB mstr_standard
J 0
(700 3450);
DISPLAY 0.787234 (700 3450);
PAINT MONO (700 3450);
DISPLAY INVISIBLE (700 3450);
FORCEPROP 1 LAST BODY_TYPE PLUMBING
J 2
(700 3400);
DISPLAY 1.234043 (700 3400);
PAINT GREEN (700 3400);
DISPLAY INVISIBLE (700 3400);
FORCEPROP 1 LAST HDL_TAP TRUE
J 2
(375 3325);
DISPLAY 1.234043 (375 3325);
PAINT GREEN (375 3325);
DISPLAY INVISIBLE (375 3325);
FORCEPROP 1 LAST PATH I41
J 2
(700 3450);
DISPLAY 0.936170 (700 3450);
PAINT GREEN (700 3450);
DISPLAY INVISIBLE (700 3450);
FORCEADD SCONN288_H44441004..3
(1800 2400);
FORCEPROP 1 LAST LOCATION J1A2
J 0
(1350 3800);
DISPLAY 0.617021 (1350 3800);
PAINT AQUA (1350 3800);
FORCEPROP 1 LAST PART_NUMBER H44441-004
J 0
(1350 1050);
DISPLAY 0.617021 (1350 1050);
PAINT BLUE (1350 1050);
FORCEPROP 1 LAST MATERIAL SCONN
J 0
(1350 3750);
DISPLAY 0.617021 (1350 3750);
PAINT SKYBLUE (1350 3750);
FORCEPROP 2 LASTPIN (1300 3550) $PN 2
J 2
(1290 3560);
DISPLAY 0.617021 (1290 3560);
PAINT ORANGE (1290 3560);
FORCEPROP 2 LASTPIN (1300 3500) $PN 4
J 2
(1290 3510);
DISPLAY 0.617021 (1290 3510);
PAINT ORANGE (1290 3510);
FORCEPROP 2 LASTPIN (1300 3450) $PN 6
J 2
(1290 3460);
DISPLAY 0.617021 (1290 3460);
PAINT ORANGE (1290 3460);
FORCEPROP 2 LASTPIN (1300 3400) $PN 9
J 2
(1290 3410);
DISPLAY 0.617021 (1290 3410);
PAINT ORANGE (1290 3410);
FORCEPROP 2 LASTPIN (1300 3350) $PN 11
J 2
(1290 3360);
DISPLAY 0.617021 (1290 3360);
PAINT ORANGE (1290 3360);
FORCEPROP 2 LASTPIN (1300 3300) $PN 13
J 2
(1290 3310);
DISPLAY 0.617021 (1290 3310);
PAINT ORANGE (1290 3310);
FORCEPROP 2 LASTPIN (1300 3250) $PN 15
J 2
(1290 3260);
DISPLAY 0.617021 (1290 3260);
PAINT ORANGE (1290 3260);
FORCEPROP 2 LASTPIN (1300 3200) $PN 17
J 2
(1290 3210);
DISPLAY 0.617021 (1290 3210);
PAINT ORANGE (1290 3210);
FORCEPROP 2 LASTPIN (1300 3150) $PN 20
J 2
(1290 3160);
DISPLAY 0.617021 (1290 3160);
PAINT ORANGE (1290 3160);
FORCEPROP 2 LASTPIN (1300 3100) $PN 22
J 2
(1290 3110);
DISPLAY 0.617021 (1290 3110);
PAINT ORANGE (1290 3110);
FORCEPROP 2 LASTPIN (1300 3050) $PN 24
J 2
(1290 3060);
DISPLAY 0.617021 (1290 3060);
PAINT ORANGE (1290 3060);
FORCEPROP 2 LASTPIN (1300 3000) $PN 26
J 2
(1290 3010);
DISPLAY 0.617021 (1290 3010);
PAINT ORANGE (1290 3010);
FORCEPROP 2 LASTPIN (1300 2950) $PN 28
J 2
(1290 2960);
DISPLAY 0.617021 (1290 2960);
PAINT ORANGE (1290 2960);
FORCEPROP 2 LASTPIN (1300 2900) $PN 31
J 2
(1290 2910);
DISPLAY 0.617021 (1290 2910);
PAINT ORANGE (1290 2910);
FORCEPROP 2 LASTPIN (1300 2850) $PN 33
J 2
(1290 2860);
DISPLAY 0.617021 (1290 2860);
PAINT ORANGE (1290 2860);
FORCEPROP 2 LASTPIN (1300 2800) $PN 35
J 2
(1290 2810);
DISPLAY 0.617021 (1290 2810);
PAINT ORANGE (1290 2810);
FORCEPROP 2 LASTPIN (1300 2750) $PN 37
J 2
(1290 2760);
DISPLAY 0.617021 (1290 2760);
PAINT ORANGE (1290 2760);
FORCEPROP 2 LASTPIN (1300 2700) $PN 39
J 2
(1290 2710);
DISPLAY 0.617021 (1290 2710);
PAINT ORANGE (1290 2710);
FORCEPROP 2 LASTPIN (1300 2650) $PN 42
J 2
(1290 2660);
DISPLAY 0.617021 (1290 2660);
PAINT ORANGE (1290 2660);
FORCEPROP 2 LASTPIN (1300 2600) $PN 44
J 2
(1290 2610);
DISPLAY 0.617021 (1290 2610);
PAINT ORANGE (1290 2610);
FORCEPROP 2 LASTPIN (1300 2550) $PN 46
J 2
(1290 2560);
DISPLAY 0.617021 (1290 2560);
PAINT ORANGE (1290 2560);
FORCEPROP 2 LASTPIN (1300 2500) $PN 48
J 2
(1290 2510);
DISPLAY 0.617021 (1290 2510);
PAINT ORANGE (1290 2510);
FORCEPROP 2 LASTPIN (1300 2450) $PN 50
J 2
(1290 2460);
DISPLAY 0.617021 (1290 2460);
PAINT ORANGE (1290 2460);
FORCEPROP 2 LASTPIN (1300 2400) $PN 53
J 2
(1290 2410);
DISPLAY 0.617021 (1290 2410);
PAINT ORANGE (1290 2410);
FORCEPROP 2 LASTPIN (1300 2350) $PN 55
J 2
(1290 2360);
DISPLAY 0.617021 (1290 2360);
PAINT ORANGE (1290 2360);
FORCEPROP 2 LASTPIN (1300 2300) $PN 57
J 2
(1290 2310);
DISPLAY 0.617021 (1290 2310);
PAINT ORANGE (1290 2310);
FORCEPROP 2 LASTPIN (1300 2250) $PN 94
J 2
(1290 2260);
DISPLAY 0.617021 (1290 2260);
PAINT ORANGE (1290 2260);
FORCEPROP 2 LASTPIN (1300 2200) $PN 96
J 2
(1290 2210);
DISPLAY 0.617021 (1290 2210);
PAINT ORANGE (1290 2210);
FORCEPROP 2 LASTPIN (1300 2150) $PN 98
J 2
(1290 2160);
DISPLAY 0.617021 (1290 2160);
PAINT ORANGE (1290 2160);
FORCEPROP 2 LASTPIN (1300 2100) $PN 101
J 2
(1290 2110);
DISPLAY 0.617021 (1290 2110);
PAINT ORANGE (1290 2110);
FORCEPROP 2 LASTPIN (1300 2050) $PN 103
J 2
(1290 2060);
DISPLAY 0.617021 (1290 2060);
PAINT ORANGE (1290 2060);
FORCEPROP 2 LASTPIN (1300 2000) $PN 105
J 2
(1290 2010);
DISPLAY 0.617021 (1290 2010);
PAINT ORANGE (1290 2010);
FORCEPROP 2 LASTPIN (1300 1950) $PN 107
J 2
(1290 1960);
DISPLAY 0.617021 (1290 1960);
PAINT ORANGE (1290 1960);
FORCEPROP 2 LASTPIN (1300 1900) $PN 109
J 2
(1290 1910);
DISPLAY 0.617021 (1290 1910);
PAINT ORANGE (1290 1910);
FORCEPROP 2 LASTPIN (1300 1850) $PN 112
J 2
(1290 1860);
DISPLAY 0.617021 (1290 1860);
PAINT ORANGE (1290 1860);
FORCEPROP 2 LASTPIN (1300 1800) $PN 114
J 2
(1290 1810);
DISPLAY 0.617021 (1290 1810);
PAINT ORANGE (1290 1810);
FORCEPROP 2 LASTPIN (1300 1750) $PN 116
J 2
(1290 1760);
DISPLAY 0.617021 (1290 1760);
PAINT ORANGE (1290 1760);
FORCEPROP 2 LASTPIN (1300 1700) $PN 118
J 2
(1290 1710);
DISPLAY 0.617021 (1290 1710);
PAINT ORANGE (1290 1710);
FORCEPROP 2 LASTPIN (1300 1650) $PN 120
J 2
(1290 1660);
DISPLAY 0.617021 (1290 1660);
PAINT ORANGE (1290 1660);
FORCEPROP 2 LASTPIN (1300 1600) $PN 123
J 2
(1290 1610);
DISPLAY 0.617021 (1290 1610);
PAINT ORANGE (1290 1610);
FORCEPROP 2 LASTPIN (1300 1550) $PN 125
J 2
(1290 1560);
DISPLAY 0.617021 (1290 1560);
PAINT ORANGE (1290 1560);
FORCEPROP 2 LASTPIN (1300 1500) $PN 127
J 2
(1290 1510);
DISPLAY 0.617021 (1290 1510);
PAINT ORANGE (1290 1510);
FORCEPROP 2 LASTPIN (1300 1450) $PN 129
J 2
(1290 1460);
DISPLAY 0.617021 (1290 1460);
PAINT ORANGE (1290 1460);
FORCEPROP 2 LASTPIN (1300 1400) $PN 131
J 2
(1290 1410);
DISPLAY 0.617021 (1290 1410);
PAINT ORANGE (1290 1410);
FORCEPROP 2 LASTPIN (1300 1350) $PN 134
J 2
(1290 1360);
DISPLAY 0.617021 (1290 1360);
PAINT ORANGE (1290 1360);
FORCEPROP 2 LASTPIN (1300 1300) $PN 136
J 2
(1290 1310);
DISPLAY 0.617021 (1290 1310);
PAINT ORANGE (1290 1310);
FORCEPROP 2 LASTPIN (1300 1250) $PN 138
J 2
(1290 1260);
DISPLAY 0.617021 (1290 1260);
PAINT ORANGE (1290 1260);
FORCEPROP 2 LASTPIN (2300 3550) $PN 147
J 0
(2310 3560);
DISPLAY 0.617021 (2310 3560);
PAINT ORANGE (2310 3560);
FORCEPROP 2 LASTPIN (2300 3500) $PN 149
J 0
(2310 3510);
DISPLAY 0.617021 (2310 3510);
PAINT ORANGE (2310 3510);
FORCEPROP 2 LASTPIN (2300 3450) $PN 151
J 0
(2310 3460);
DISPLAY 0.617021 (2310 3460);
PAINT ORANGE (2310 3460);
FORCEPROP 2 LASTPIN (2300 3400) $PN 154
J 0
(2310 3410);
DISPLAY 0.617021 (2310 3410);
PAINT ORANGE (2310 3410);
FORCEPROP 2 LASTPIN (2300 3350) $PN 156
J 0
(2310 3360);
DISPLAY 0.617021 (2310 3360);
PAINT ORANGE (2310 3360);
FORCEPROP 2 LASTPIN (2300 3300) $PN 158
J 0
(2310 3310);
DISPLAY 0.617021 (2310 3310);
PAINT ORANGE (2310 3310);
FORCEPROP 2 LASTPIN (2300 3250) $PN 160
J 0
(2310 3260);
DISPLAY 0.617021 (2310 3260);
PAINT ORANGE (2310 3260);
FORCEPROP 2 LASTPIN (2300 3200) $PN 162
J 0
(2310 3210);
DISPLAY 0.617021 (2310 3210);
PAINT ORANGE (2310 3210);
FORCEPROP 2 LASTPIN (2300 3150) $PN 165
J 0
(2310 3160);
DISPLAY 0.617021 (2310 3160);
PAINT ORANGE (2310 3160);
FORCEPROP 2 LASTPIN (2300 3100) $PN 167
J 0
(2310 3110);
DISPLAY 0.617021 (2310 3110);
PAINT ORANGE (2310 3110);
FORCEPROP 2 LASTPIN (2300 3050) $PN 169
J 0
(2310 3060);
DISPLAY 0.617021 (2310 3060);
PAINT ORANGE (2310 3060);
FORCEPROP 2 LASTPIN (2300 3000) $PN 171
J 0
(2310 3010);
DISPLAY 0.617021 (2310 3010);
PAINT ORANGE (2310 3010);
FORCEPROP 2 LASTPIN (2300 2950) $PN 173
J 0
(2310 2960);
DISPLAY 0.617021 (2310 2960);
PAINT ORANGE (2310 2960);
FORCEPROP 2 LASTPIN (2300 2900) $PN 176
J 0
(2310 2910);
DISPLAY 0.617021 (2310 2910);
PAINT ORANGE (2310 2910);
FORCEPROP 2 LASTPIN (2300 2850) $PN 178
J 0
(2310 2860);
DISPLAY 0.617021 (2310 2860);
PAINT ORANGE (2310 2860);
FORCEPROP 2 LASTPIN (2300 2800) $PN 180
J 0
(2310 2810);
DISPLAY 0.617021 (2310 2810);
PAINT ORANGE (2310 2810);
FORCEPROP 2 LASTPIN (2300 2750) $PN 182
J 0
(2310 2760);
DISPLAY 0.617021 (2310 2760);
PAINT ORANGE (2310 2760);
FORCEPROP 2 LASTPIN (2300 2700) $PN 184
J 0
(2310 2710);
DISPLAY 0.617021 (2310 2710);
PAINT ORANGE (2310 2710);
FORCEPROP 2 LASTPIN (2300 2650) $PN 187
J 0
(2310 2660);
DISPLAY 0.617021 (2310 2660);
PAINT ORANGE (2310 2660);
FORCEPROP 2 LASTPIN (2300 2600) $PN 189
J 0
(2310 2610);
DISPLAY 0.617021 (2310 2610);
PAINT ORANGE (2310 2610);
FORCEPROP 2 LASTPIN (2300 2550) $PN 191
J 0
(2310 2560);
DISPLAY 0.617021 (2310 2560);
PAINT ORANGE (2310 2560);
FORCEPROP 2 LASTPIN (2300 2500) $PN 193
J 0
(2310 2510);
DISPLAY 0.617021 (2310 2510);
PAINT ORANGE (2310 2510);
FORCEPROP 2 LASTPIN (2300 2450) $PN 195
J 0
(2310 2460);
DISPLAY 0.617021 (2310 2460);
PAINT ORANGE (2310 2460);
FORCEPROP 2 LASTPIN (2300 2400) $PN 198
J 0
(2310 2410);
DISPLAY 0.617021 (2310 2410);
PAINT ORANGE (2310 2410);
FORCEPROP 2 LASTPIN (2300 2350) $PN 200
J 0
(2310 2360);
DISPLAY 0.617021 (2310 2360);
PAINT ORANGE (2310 2360);
FORCEPROP 2 LASTPIN (2300 2300) $PN 202
J 0
(2310 2310);
DISPLAY 0.617021 (2310 2310);
PAINT ORANGE (2310 2310);
FORCEPROP 2 LASTPIN (2300 2250) $PN 239
J 0
(2310 2260);
DISPLAY 0.617021 (2310 2260);
PAINT ORANGE (2310 2260);
FORCEPROP 2 LASTPIN (2300 2200) $PN 241
J 0
(2310 2210);
DISPLAY 0.617021 (2310 2210);
PAINT ORANGE (2310 2210);
FORCEPROP 2 LASTPIN (2300 2150) $PN 243
J 0
(2310 2160);
DISPLAY 0.617021 (2310 2160);
PAINT ORANGE (2310 2160);
FORCEPROP 2 LASTPIN (2300 2100) $PN 246
J 0
(2310 2110);
DISPLAY 0.617021 (2310 2110);
PAINT ORANGE (2310 2110);
FORCEPROP 2 LASTPIN (2300 2050) $PN 248
J 0
(2310 2060);
DISPLAY 0.617021 (2310 2060);
PAINT ORANGE (2310 2060);
FORCEPROP 2 LASTPIN (2300 2000) $PN 250
J 0
(2310 2010);
DISPLAY 0.617021 (2310 2010);
PAINT ORANGE (2310 2010);
FORCEPROP 2 LASTPIN (2300 1950) $PN 252
J 0
(2310 1960);
DISPLAY 0.617021 (2310 1960);
PAINT ORANGE (2310 1960);
FORCEPROP 2 LASTPIN (2300 1900) $PN 254
J 0
(2310 1910);
DISPLAY 0.617021 (2310 1910);
PAINT ORANGE (2310 1910);
FORCEPROP 2 LASTPIN (2300 1850) $PN 257
J 0
(2310 1860);
DISPLAY 0.617021 (2310 1860);
PAINT ORANGE (2310 1860);
FORCEPROP 2 LASTPIN (2300 1800) $PN 259
J 0
(2310 1810);
DISPLAY 0.617021 (2310 1810);
PAINT ORANGE (2310 1810);
FORCEPROP 2 LASTPIN (2300 1750) $PN 261
J 0
(2310 1760);
DISPLAY 0.617021 (2310 1760);
PAINT ORANGE (2310 1760);
FORCEPROP 2 LASTPIN (2300 1700) $PN 263
J 0
(2310 1710);
DISPLAY 0.617021 (2310 1710);
PAINT ORANGE (2310 1710);
FORCEPROP 2 LASTPIN (2300 1650) $PN 265
J 0
(2310 1660);
DISPLAY 0.617021 (2310 1660);
PAINT ORANGE (2310 1660);
FORCEPROP 2 LASTPIN (2300 1600) $PN 268
J 0
(2310 1610);
DISPLAY 0.617021 (2310 1610);
PAINT ORANGE (2310 1610);
FORCEPROP 2 LASTPIN (2300 1550) $PN 270
J 0
(2310 1560);
DISPLAY 0.617021 (2310 1560);
PAINT ORANGE (2310 1560);
FORCEPROP 2 LASTPIN (2300 1500) $PN 272
J 0
(2310 1510);
DISPLAY 0.617021 (2310 1510);
PAINT ORANGE (2310 1510);
FORCEPROP 2 LASTPIN (2300 1450) $PN 274
J 0
(2310 1460);
DISPLAY 0.617021 (2310 1460);
PAINT ORANGE (2310 1460);
FORCEPROP 2 LASTPIN (2300 1400) $PN 276
J 0
(2310 1410);
DISPLAY 0.617021 (2310 1410);
PAINT ORANGE (2310 1410);
FORCEPROP 2 LASTPIN (2300 1350) $PN 279
J 0
(2310 1360);
DISPLAY 0.617021 (2310 1360);
PAINT ORANGE (2310 1360);
FORCEPROP 2 LASTPIN (2300 1300) $PN 281
J 0
(2310 1310);
DISPLAY 0.617021 (2310 1310);
PAINT ORANGE (2310 1310);
FORCEPROP 2 LASTPIN (2300 1250) $PN 283
J 0
(2310 1260);
DISPLAY 0.617021 (2310 1260);
PAINT ORANGE (2310 1260);
FORCEPROP 1 LAST PACK_TYPE PIP
J 0
(1350 3850);
PAINT SKYBLUE (1350 3850);
DISPLAY INVISIBLE (1350 3850);
FORCEPROP 2 LAST BOM_COST MEM
J 0
(1800 2400);
PAINT ORANGE (1800 2400);
DISPLAY INVISIBLE (1800 2400);
FORCEPROP 2 LAST CDS_LIB mstr_sconn
J 0
(1800 2400);
PAINT ORANGE (1800 2400);
DISPLAY INVISIBLE (1800 2400);
FORCEPROP 2 LAST SEC_TYPE PIP
J 0
(1350 3850);
DISPLAY 1.021277 (1350 3850);
PAINT ORANGE (1350 3850);
DISPLAY INVISIBLE (1350 3850);
FORCEPROP 2 LAST SEC 3
J 0
(1350 3850);
DISPLAY 0.680851 (1350 3850);
PAINT MONO (1350 3850);
DISPLAY INVISIBLE (1350 3850);
FORCEPROP 2 LAST CDS_LOCATION J1A2
J 0
(1350 3800);
DISPLAY 0.617021 (1350 3800);
PAINT AQUA (1350 3800);
DISPLAY INVISIBLE (1350 3800);
FORCEPROP 1 LAST PATH I43
J 0
(1800 3750);
PAINT GREEN (1800 3750);
DISPLAY INVISIBLE (1800 3750);
FORCEPROP 2 LAST ROOM DDR4_CH_L
J 0
(1800 2400);
PAINT ORANGE (1800 2400);
DISPLAY INVISIBLE (1800 2400);
FORCEADD GND..1
R 2
(1100 1100);
FORCEPROP 3 LASTPIN (1100 1150) SIG_NAME GND\g
J 0
(1110 1160);
DISPLAY 0.659574 (1110 1160);
PAINT MONO (1110 1160);
DISPLAY INVISIBLE (1110 1160);
FORCEPROP 1 LAST VOLTAGE 0
J 0
(1100 1100);
PAINT SKYBLUE (1100 1100);
DISPLAY INVISIBLE (1100 1100);
FORCEPROP 2 LAST BOM_COST MEM
J 0
(1100 1105);
PAINT ORANGE (1100 1105);
DISPLAY INVISIBLE (1100 1105);
FORCEPROP 2 LAST CDS_LIB mstr_symbols
J 0
(1100 1100);
DISPLAY 0.787234 (1100 1100);
PAINT MONO (1100 1100);
DISPLAY INVISIBLE (1100 1100);
FORCEPROP 1 LAST SIZE 1B
J 2
(1025 1050);
DISPLAY 1.170213 (1025 1050);
PAINT GREEN (1025 1050);
DISPLAY INVISIBLE (1025 1050);
FORCEPROP 1 LAST BODY_TYPE PLUMBING
J 2
(1145 1057);
DISPLAY 0.340426 (1145 1057);
PAINT GREEN (1145 1057);
DISPLAY INVISIBLE (1145 1057);
FORCEPROP 1 LAST PATH I44
J 2
(1025 1100);
DISPLAY 0.936170 (1025 1100);
PAINT GREEN (1025 1100);
DISPLAY INVISIBLE (1025 1100);
FORCEPROP 2 LAST ROOM DDR4_CH_D
J 0
(1100 1105);
PAINT ORANGE (1100 1105);
DISPLAY INVISIBLE (1100 1105);
FORCEPROP 1 LAST HDL_POWER GND
J 2
(1100 1250);
DISPLAY 0.553191 (1100 1250);
PAINT GREEN (1100 1250);
DISPLAY INVISIBLE (1100 1250);
FORCEADD OFFPAGE..3
(-1175 4950);
FORCEPROP 2 LAST $XR0 61 
J 0
(-961 4950);
DISPLAY 0.638298 (-961 4950);
PAINT MONO (-961 4950);
FORCEPROP 2 LAST $XR1 86 
J 0
(-871 4950);
DISPLAY 0.638298 (-871 4950);
PAINT MONO (-871 4950);
FORCEPROP 2 LAST CDS_LIB mstr_standard
J 0
(-1175 4950);
DISPLAY 0.787234 (-1175 4950);
PAINT MONO (-1175 4950);
DISPLAY INVISIBLE (-1175 4950);
FORCEPROP 1 LAST OFFPAGE TRUE
J 0
(-850 4825);
DISPLAY 0.936170 (-850 4825);
PAINT GREEN (-850 4825);
DISPLAY INVISIBLE (-850 4825);
FORCEPROP 1 LAST COMMENT_BODY TRUE
J 0
(-1225 4850);
DISPLAY 0.936170 (-1225 4850);
PAINT GREEN (-1225 4850);
DISPLAY INVISIBLE (-1225 4850);
FORCEPROP 2 LAST PATH I45
J 0
(-975 5025);
DISPLAY 0.787234 (-975 5025);
PAINT MONO (-975 5025);
DISPLAY INVISIBLE (-975 5025);
FORCEADD TAP..6
R 2
(-1750 4800);
FORCEPROP 3 LASTPIN (-1800 4800) SIG_NAME M_L_DQ<60>
J 0
(-1790 4810);
DISPLAY 0.659574 (-1790 4810);
PAINT MONO (-1790 4810);
DISPLAY INVISIBLE (-1790 4810);
FORCEPROP 1 LASTPIN (-1800 4800) BN 60
J 2
(-1750 4810);
DISPLAY 0.617021 (-1750 4810);
PAINT PINK (-1750 4810);
FORCEPROP 2 LAST CDS_LIB mstr_standard
J 2
(-1750 4800);
DISPLAY 0.787234 (-1750 4800);
PAINT MONO (-1750 4800);
DISPLAY INVISIBLE (-1750 4800);
FORCEPROP 1 LAST BODY_TYPE PLUMBING
J 2
(-1750 4750);
DISPLAY 1.234043 (-1750 4750);
PAINT GREEN (-1750 4750);
DISPLAY INVISIBLE (-1750 4750);
FORCEPROP 1 LAST HDL_TAP TRUE
J 2
(-2075 4675);
DISPLAY 1.234043 (-2075 4675);
PAINT GREEN (-2075 4675);
DISPLAY INVISIBLE (-2075 4675);
FORCEPROP 1 LAST PATH I46
J 2
(-1750 4800);
DISPLAY 0.936170 (-1750 4800);
PAINT GREEN (-1750 4800);
DISPLAY INVISIBLE (-1750 4800);
FORCEADD TAP..6
R 2
(-1750 4750);
FORCEPROP 3 LASTPIN (-1800 4750) SIG_NAME M_L_DQ<61>
J 0
(-1790 4760);
DISPLAY 0.659574 (-1790 4760);
PAINT MONO (-1790 4760);
DISPLAY INVISIBLE (-1790 4760);
FORCEPROP 1 LASTPIN (-1800 4750) BN 61
J 2
(-1750 4760);
DISPLAY 0.617021 (-1750 4760);
PAINT PINK (-1750 4760);
FORCEPROP 2 LAST CDS_LIB mstr_standard
J 2
(-1750 4750);
DISPLAY 0.787234 (-1750 4750);
PAINT MONO (-1750 4750);
DISPLAY INVISIBLE (-1750 4750);
FORCEPROP 1 LAST BODY_TYPE PLUMBING
J 2
(-1750 4700);
DISPLAY 1.234043 (-1750 4700);
PAINT GREEN (-1750 4700);
DISPLAY INVISIBLE (-1750 4700);
FORCEPROP 1 LAST HDL_TAP TRUE
J 2
(-2075 4625);
DISPLAY 1.234043 (-2075 4625);
PAINT GREEN (-2075 4625);
DISPLAY INVISIBLE (-2075 4625);
FORCEPROP 1 LAST PATH I47
J 2
(-1750 4750);
DISPLAY 0.936170 (-1750 4750);
PAINT GREEN (-1750 4750);
DISPLAY INVISIBLE (-1750 4750);
FORCEADD TAP..6
R 2
(-1750 4850);
FORCEPROP 3 LASTPIN (-1800 4850) SIG_NAME M_L_DQ<63>
J 0
(-1790 4860);
DISPLAY 0.659574 (-1790 4860);
PAINT MONO (-1790 4860);
DISPLAY INVISIBLE (-1790 4860);
FORCEPROP 1 LASTPIN (-1800 4850) BN 63
J 2
(-1750 4860);
DISPLAY 0.617021 (-1750 4860);
PAINT PINK (-1750 4860);
FORCEPROP 2 LAST CDS_LIB mstr_standard
J 2
(-1750 4850);
DISPLAY 0.787234 (-1750 4850);
PAINT MONO (-1750 4850);
DISPLAY INVISIBLE (-1750 4850);
FORCEPROP 1 LAST BODY_TYPE PLUMBING
J 2
(-1750 4800);
DISPLAY 1.234043 (-1750 4800);
PAINT GREEN (-1750 4800);
DISPLAY INVISIBLE (-1750 4800);
FORCEPROP 1 LAST HDL_TAP TRUE
J 2
(-2075 4725);
DISPLAY 1.234043 (-2075 4725);
PAINT GREEN (-2075 4725);
DISPLAY INVISIBLE (-2075 4725);
FORCEPROP 1 LAST PATH I48
J 2
(-1750 4850);
DISPLAY 0.936170 (-1750 4850);
PAINT GREEN (-1750 4850);
DISPLAY INVISIBLE (-1750 4850);
FORCEADD TAP..6
R 2
(-1750 4900);
FORCEPROP 3 LASTPIN (-1800 4900) SIG_NAME M_L_DQ<62>
J 0
(-1790 4910);
DISPLAY 0.659574 (-1790 4910);
PAINT MONO (-1790 4910);
DISPLAY INVISIBLE (-1790 4910);
FORCEPROP 1 LASTPIN (-1800 4900) BN 62
J 2
(-1750 4910);
DISPLAY 0.617021 (-1750 4910);
PAINT PINK (-1750 4910);
FORCEPROP 2 LAST CDS_LIB mstr_standard
J 2
(-1750 4900);
DISPLAY 0.787234 (-1750 4900);
PAINT MONO (-1750 4900);
DISPLAY INVISIBLE (-1750 4900);
FORCEPROP 1 LAST BODY_TYPE PLUMBING
J 2
(-1750 4850);
DISPLAY 1.234043 (-1750 4850);
PAINT GREEN (-1750 4850);
DISPLAY INVISIBLE (-1750 4850);
FORCEPROP 1 LAST HDL_TAP TRUE
J 2
(-2075 4775);
DISPLAY 1.234043 (-2075 4775);
PAINT GREEN (-2075 4775);
DISPLAY INVISIBLE (-2075 4775);
FORCEPROP 1 LAST PATH I49
J 2
(-1750 4900);
DISPLAY 0.936170 (-1750 4900);
PAINT GREEN (-1750 4900);
DISPLAY INVISIBLE (-1750 4900);
FORCEADD TAP..6
R 2
(900 5000);
FORCEPROP 3 LASTPIN (850 5000) SIG_NAME M_L_DQS_DN<16>
J 0
(860 5010);
DISPLAY 0.659574 (860 5010);
PAINT MONO (860 5010);
DISPLAY INVISIBLE (860 5010);
FORCEPROP 1 LASTPIN (850 5000) BN 16
J 2
(900 5010);
DISPLAY 0.617021 (900 5010);
PAINT PINK (900 5010);
FORCEPROP 2 LAST CDS_LIB mstr_standard
J 0
(900 5000);
DISPLAY 0.787234 (900 5000);
PAINT MONO (900 5000);
DISPLAY INVISIBLE (900 5000);
FORCEPROP 1 LAST BODY_TYPE PLUMBING
J 2
(900 4950);
DISPLAY 1.234043 (900 4950);
PAINT GREEN (900 4950);
DISPLAY INVISIBLE (900 4950);
FORCEPROP 1 LAST HDL_TAP TRUE
J 2
(575 4875);
DISPLAY 1.234043 (575 4875);
PAINT GREEN (575 4875);
DISPLAY INVISIBLE (575 4875);
FORCEPROP 1 LAST PATH I5
J 2
(900 5000);
DISPLAY 0.936170 (900 5000);
PAINT GREEN (900 5000);
DISPLAY INVISIBLE (900 5000);
FORCEADD TAP..6
R 2
(-1750 4500);
FORCEPROP 3 LASTPIN (-1800 4500) SIG_NAME M_L_DQ<54>
J 0
(-1790 4510);
DISPLAY 0.659574 (-1790 4510);
PAINT MONO (-1790 4510);
DISPLAY INVISIBLE (-1790 4510);
FORCEPROP 1 LASTPIN (-1800 4500) BN 54
J 2
(-1750 4510);
DISPLAY 0.617021 (-1750 4510);
PAINT PINK (-1750 4510);
FORCEPROP 2 LAST CDS_LIB mstr_standard
J 2
(-1750 4500);
DISPLAY 0.787234 (-1750 4500);
PAINT MONO (-1750 4500);
DISPLAY INVISIBLE (-1750 4500);
FORCEPROP 1 LAST BODY_TYPE PLUMBING
J 2
(-1750 4450);
DISPLAY 1.234043 (-1750 4450);
PAINT GREEN (-1750 4450);
DISPLAY INVISIBLE (-1750 4450);
FORCEPROP 1 LAST HDL_TAP TRUE
J 2
(-2075 4375);
DISPLAY 1.234043 (-2075 4375);
PAINT GREEN (-2075 4375);
DISPLAY INVISIBLE (-2075 4375);
FORCEPROP 1 LAST PATH I50
J 2
(-1750 4500);
DISPLAY 0.936170 (-1750 4500);
PAINT GREEN (-1750 4500);
DISPLAY INVISIBLE (-1750 4500);
FORCEADD TAP..6
R 2
(-1750 4550);
FORCEPROP 3 LASTPIN (-1800 4550) SIG_NAME M_L_DQ<57>
J 0
(-1790 4560);
DISPLAY 0.659574 (-1790 4560);
PAINT MONO (-1790 4560);
DISPLAY INVISIBLE (-1790 4560);
FORCEPROP 1 LASTPIN (-1800 4550) BN 57
J 2
(-1750 4560);
DISPLAY 0.617021 (-1750 4560);
PAINT PINK (-1750 4560);
FORCEPROP 2 LAST CDS_LIB mstr_standard
J 2
(-1750 4550);
DISPLAY 0.787234 (-1750 4550);
PAINT MONO (-1750 4550);
DISPLAY INVISIBLE (-1750 4550);
FORCEPROP 1 LAST BODY_TYPE PLUMBING
J 2
(-1750 4500);
DISPLAY 1.234043 (-1750 4500);
PAINT GREEN (-1750 4500);
DISPLAY INVISIBLE (-1750 4500);
FORCEPROP 1 LAST HDL_TAP TRUE
J 2
(-2075 4425);
DISPLAY 1.234043 (-2075 4425);
PAINT GREEN (-2075 4425);
DISPLAY INVISIBLE (-2075 4425);
FORCEPROP 1 LAST PATH I51
J 2
(-1750 4550);
DISPLAY 0.936170 (-1750 4550);
PAINT GREEN (-1750 4550);
DISPLAY INVISIBLE (-1750 4550);
FORCEADD TAP..6
R 2
(-1750 4650);
FORCEPROP 3 LASTPIN (-1800 4650) SIG_NAME M_L_DQ<59>
J 0
(-1790 4660);
DISPLAY 0.659574 (-1790 4660);
PAINT MONO (-1790 4660);
DISPLAY INVISIBLE (-1790 4660);
FORCEPROP 1 LASTPIN (-1800 4650) BN 59
J 2
(-1750 4660);
DISPLAY 0.617021 (-1750 4660);
PAINT PINK (-1750 4660);
FORCEPROP 2 LAST CDS_LIB mstr_standard
J 2
(-1750 4650);
DISPLAY 0.787234 (-1750 4650);
PAINT MONO (-1750 4650);
DISPLAY INVISIBLE (-1750 4650);
FORCEPROP 1 LAST BODY_TYPE PLUMBING
J 2
(-1750 4600);
DISPLAY 1.234043 (-1750 4600);
PAINT GREEN (-1750 4600);
DISPLAY INVISIBLE (-1750 4600);
FORCEPROP 1 LAST HDL_TAP TRUE
J 2
(-2075 4525);
DISPLAY 1.234043 (-2075 4525);
PAINT GREEN (-2075 4525);
DISPLAY INVISIBLE (-2075 4525);
FORCEPROP 1 LAST PATH I52
J 2
(-1750 4650);
DISPLAY 0.936170 (-1750 4650);
PAINT GREEN (-1750 4650);
DISPLAY INVISIBLE (-1750 4650);
FORCEADD TAP..6
R 2
(-1750 4600);
FORCEPROP 3 LASTPIN (-1800 4600) SIG_NAME M_L_DQ<56>
J 0
(-1790 4610);
DISPLAY 0.659574 (-1790 4610);
PAINT MONO (-1790 4610);
DISPLAY INVISIBLE (-1790 4610);
FORCEPROP 1 LASTPIN (-1800 4600) BN 56
J 2
(-1750 4610);
DISPLAY 0.617021 (-1750 4610);
PAINT PINK (-1750 4610);
FORCEPROP 2 LAST CDS_LIB mstr_standard
J 2
(-1750 4600);
DISPLAY 0.787234 (-1750 4600);
PAINT MONO (-1750 4600);
DISPLAY INVISIBLE (-1750 4600);
FORCEPROP 1 LAST BODY_TYPE PLUMBING
J 2
(-1750 4550);
DISPLAY 1.234043 (-1750 4550);
PAINT GREEN (-1750 4550);
DISPLAY INVISIBLE (-1750 4550);
FORCEPROP 1 LAST HDL_TAP TRUE
J 2
(-2075 4475);
DISPLAY 1.234043 (-2075 4475);
PAINT GREEN (-2075 4475);
DISPLAY INVISIBLE (-2075 4475);
FORCEPROP 1 LAST PATH I53
J 2
(-1750 4600);
DISPLAY 0.936170 (-1750 4600);
PAINT GREEN (-1750 4600);
DISPLAY INVISIBLE (-1750 4600);
FORCEADD TAP..6
R 2
(-1750 4700);
FORCEPROP 3 LASTPIN (-1800 4700) SIG_NAME M_L_DQ<58>
J 0
(-1790 4710);
DISPLAY 0.659574 (-1790 4710);
PAINT MONO (-1790 4710);
DISPLAY INVISIBLE (-1790 4710);
FORCEPROP 1 LASTPIN (-1800 4700) BN 58
J 2
(-1750 4710);
DISPLAY 0.617021 (-1750 4710);
PAINT PINK (-1750 4710);
FORCEPROP 2 LAST CDS_LIB mstr_standard
J 2
(-1750 4700);
DISPLAY 0.787234 (-1750 4700);
PAINT MONO (-1750 4700);
DISPLAY INVISIBLE (-1750 4700);
FORCEPROP 1 LAST BODY_TYPE PLUMBING
J 2
(-1750 4650);
DISPLAY 1.234043 (-1750 4650);
PAINT GREEN (-1750 4650);
DISPLAY INVISIBLE (-1750 4650);
FORCEPROP 1 LAST HDL_TAP TRUE
J 2
(-2075 4575);
DISPLAY 1.234043 (-2075 4575);
PAINT GREEN (-2075 4575);
DISPLAY INVISIBLE (-2075 4575);
FORCEPROP 1 LAST PATH I54
J 2
(-1750 4700);
DISPLAY 0.936170 (-1750 4700);
PAINT GREEN (-1750 4700);
DISPLAY INVISIBLE (-1750 4700);
FORCEADD TAP..6
R 2
(-1750 4250);
FORCEPROP 3 LASTPIN (-1800 4250) SIG_NAME M_L_DQ<51>
J 0
(-1790 4260);
DISPLAY 0.659574 (-1790 4260);
PAINT MONO (-1790 4260);
DISPLAY INVISIBLE (-1790 4260);
FORCEPROP 1 LASTPIN (-1800 4250) BN 51
J 2
(-1750 4260);
DISPLAY 0.617021 (-1750 4260);
PAINT PINK (-1750 4260);
FORCEPROP 2 LAST CDS_LIB mstr_standard
J 2
(-1750 4250);
DISPLAY 0.787234 (-1750 4250);
PAINT MONO (-1750 4250);
DISPLAY INVISIBLE (-1750 4250);
FORCEPROP 1 LAST BODY_TYPE PLUMBING
J 2
(-1750 4200);
DISPLAY 1.234043 (-1750 4200);
PAINT GREEN (-1750 4200);
DISPLAY INVISIBLE (-1750 4200);
FORCEPROP 1 LAST HDL_TAP TRUE
J 2
(-2075 4125);
DISPLAY 1.234043 (-2075 4125);
PAINT GREEN (-2075 4125);
DISPLAY INVISIBLE (-2075 4125);
FORCEPROP 1 LAST PATH I55
J 2
(-1750 4250);
DISPLAY 0.936170 (-1750 4250);
PAINT GREEN (-1750 4250);
DISPLAY INVISIBLE (-1750 4250);
FORCEADD TAP..6
R 2
(-1750 4300);
FORCEPROP 3 LASTPIN (-1800 4300) SIG_NAME M_L_DQ<50>
J 0
(-1790 4310);
DISPLAY 0.659574 (-1790 4310);
PAINT MONO (-1790 4310);
DISPLAY INVISIBLE (-1790 4310);
FORCEPROP 1 LASTPIN (-1800 4300) BN 50
J 2
(-1750 4310);
DISPLAY 0.617021 (-1750 4310);
PAINT PINK (-1750 4310);
FORCEPROP 2 LAST CDS_LIB mstr_standard
J 2
(-1750 4300);
DISPLAY 0.787234 (-1750 4300);
PAINT MONO (-1750 4300);
DISPLAY INVISIBLE (-1750 4300);
FORCEPROP 1 LAST BODY_TYPE PLUMBING
J 2
(-1750 4250);
DISPLAY 1.234043 (-1750 4250);
PAINT GREEN (-1750 4250);
DISPLAY INVISIBLE (-1750 4250);
FORCEPROP 1 LAST HDL_TAP TRUE
J 2
(-2075 4175);
DISPLAY 1.234043 (-2075 4175);
PAINT GREEN (-2075 4175);
DISPLAY INVISIBLE (-2075 4175);
FORCEPROP 1 LAST PATH I56
J 2
(-1750 4300);
DISPLAY 0.936170 (-1750 4300);
PAINT GREEN (-1750 4300);
DISPLAY INVISIBLE (-1750 4300);
FORCEADD TAP..6
R 2
(-1750 4350);
FORCEPROP 3 LASTPIN (-1800 4350) SIG_NAME M_L_DQ<53>
J 0
(-1790 4360);
DISPLAY 0.659574 (-1790 4360);
PAINT MONO (-1790 4360);
DISPLAY INVISIBLE (-1790 4360);
FORCEPROP 1 LASTPIN (-1800 4350) BN 53
J 2
(-1750 4360);
DISPLAY 0.617021 (-1750 4360);
PAINT PINK (-1750 4360);
FORCEPROP 2 LAST CDS_LIB mstr_standard
J 2
(-1750 4350);
DISPLAY 0.787234 (-1750 4350);
PAINT MONO (-1750 4350);
DISPLAY INVISIBLE (-1750 4350);
FORCEPROP 1 LAST BODY_TYPE PLUMBING
J 2
(-1750 4300);
DISPLAY 1.234043 (-1750 4300);
PAINT GREEN (-1750 4300);
DISPLAY INVISIBLE (-1750 4300);
FORCEPROP 1 LAST HDL_TAP TRUE
J 2
(-2075 4225);
DISPLAY 1.234043 (-2075 4225);
PAINT GREEN (-2075 4225);
DISPLAY INVISIBLE (-2075 4225);
FORCEPROP 1 LAST PATH I57
J 2
(-1750 4350);
DISPLAY 0.936170 (-1750 4350);
PAINT GREEN (-1750 4350);
DISPLAY INVISIBLE (-1750 4350);
FORCEADD TAP..6
R 2
(-1750 4450);
FORCEPROP 3 LASTPIN (-1800 4450) SIG_NAME M_L_DQ<55>
J 0
(-1790 4460);
DISPLAY 0.659574 (-1790 4460);
PAINT MONO (-1790 4460);
DISPLAY INVISIBLE (-1790 4460);
FORCEPROP 1 LASTPIN (-1800 4450) BN 55
J 2
(-1750 4460);
DISPLAY 0.617021 (-1750 4460);
PAINT PINK (-1750 4460);
FORCEPROP 2 LAST CDS_LIB mstr_standard
J 2
(-1750 4450);
DISPLAY 0.787234 (-1750 4450);
PAINT MONO (-1750 4450);
DISPLAY INVISIBLE (-1750 4450);
FORCEPROP 1 LAST BODY_TYPE PLUMBING
J 2
(-1750 4400);
DISPLAY 1.234043 (-1750 4400);
PAINT GREEN (-1750 4400);
DISPLAY INVISIBLE (-1750 4400);
FORCEPROP 1 LAST HDL_TAP TRUE
J 2
(-2075 4325);
DISPLAY 1.234043 (-2075 4325);
PAINT GREEN (-2075 4325);
DISPLAY INVISIBLE (-2075 4325);
FORCEPROP 1 LAST PATH I58
J 2
(-1750 4450);
DISPLAY 0.936170 (-1750 4450);
PAINT GREEN (-1750 4450);
DISPLAY INVISIBLE (-1750 4450);
FORCEADD TAP..6
R 2
(-1750 4400);
FORCEPROP 3 LASTPIN (-1800 4400) SIG_NAME M_L_DQ<52>
J 0
(-1790 4410);
DISPLAY 0.659574 (-1790 4410);
PAINT MONO (-1790 4410);
DISPLAY INVISIBLE (-1790 4410);
FORCEPROP 1 LASTPIN (-1800 4400) BN 52
J 2
(-1750 4410);
DISPLAY 0.617021 (-1750 4410);
PAINT PINK (-1750 4410);
FORCEPROP 2 LAST CDS_LIB mstr_standard
J 2
(-1750 4400);
DISPLAY 0.787234 (-1750 4400);
PAINT MONO (-1750 4400);
DISPLAY INVISIBLE (-1750 4400);
FORCEPROP 1 LAST BODY_TYPE PLUMBING
J 2
(-1750 4350);
DISPLAY 1.234043 (-1750 4350);
PAINT GREEN (-1750 4350);
DISPLAY INVISIBLE (-1750 4350);
FORCEPROP 1 LAST HDL_TAP TRUE
J 2
(-2075 4275);
DISPLAY 1.234043 (-2075 4275);
PAINT GREEN (-2075 4275);
DISPLAY INVISIBLE (-2075 4275);
FORCEPROP 1 LAST PATH I59
J 2
(-1750 4400);
DISPLAY 0.936170 (-1750 4400);
PAINT GREEN (-1750 4400);
DISPLAY INVISIBLE (-1750 4400);
FORCEADD TAP..6
R 2
(900 4900);
FORCEPROP 3 LASTPIN (850 4900) SIG_NAME M_L_DQS_DN<15>
J 0
(860 4910);
DISPLAY 0.659574 (860 4910);
PAINT MONO (860 4910);
DISPLAY INVISIBLE (860 4910);
FORCEPROP 1 LASTPIN (850 4900) BN 15
J 2
(900 4910);
DISPLAY 0.617021 (900 4910);
PAINT PINK (900 4910);
FORCEPROP 2 LAST CDS_LIB mstr_standard
J 0
(900 4900);
DISPLAY 0.787234 (900 4900);
PAINT MONO (900 4900);
DISPLAY INVISIBLE (900 4900);
FORCEPROP 1 LAST BODY_TYPE PLUMBING
J 2
(900 4850);
DISPLAY 1.234043 (900 4850);
PAINT GREEN (900 4850);
DISPLAY INVISIBLE (900 4850);
FORCEPROP 1 LAST HDL_TAP TRUE
J 2
(575 4775);
DISPLAY 1.234043 (575 4775);
PAINT GREEN (575 4775);
DISPLAY INVISIBLE (575 4775);
FORCEPROP 1 LAST PATH I6
J 2
(900 4900);
DISPLAY 0.936170 (900 4900);
PAINT GREEN (900 4900);
DISPLAY INVISIBLE (900 4900);
FORCEADD TAP..6
R 2
(-1750 3950);
FORCEPROP 3 LASTPIN (-1800 3950) SIG_NAME M_L_DQ<45>
J 0
(-1790 3960);
DISPLAY 0.659574 (-1790 3960);
PAINT MONO (-1790 3960);
DISPLAY INVISIBLE (-1790 3960);
FORCEPROP 1 LASTPIN (-1800 3950) BN 45
J 2
(-1750 3960);
DISPLAY 0.617021 (-1750 3960);
PAINT PINK (-1750 3960);
FORCEPROP 2 LAST CDS_LIB mstr_standard
J 2
(-1750 3950);
DISPLAY 0.787234 (-1750 3950);
PAINT MONO (-1750 3950);
DISPLAY INVISIBLE (-1750 3950);
FORCEPROP 1 LAST BODY_TYPE PLUMBING
J 2
(-1750 3900);
DISPLAY 1.234043 (-1750 3900);
PAINT GREEN (-1750 3900);
DISPLAY INVISIBLE (-1750 3900);
FORCEPROP 1 LAST HDL_TAP TRUE
J 2
(-2075 3825);
DISPLAY 1.234043 (-2075 3825);
PAINT GREEN (-2075 3825);
DISPLAY INVISIBLE (-2075 3825);
FORCEPROP 1 LAST PATH I60
J 2
(-1750 3950);
DISPLAY 0.936170 (-1750 3950);
PAINT GREEN (-1750 3950);
DISPLAY INVISIBLE (-1750 3950);
FORCEADD TAP..6
R 2
(-1750 4000);
FORCEPROP 3 LASTPIN (-1800 4000) SIG_NAME M_L_DQ<44>
J 0
(-1790 4010);
DISPLAY 0.659574 (-1790 4010);
PAINT MONO (-1790 4010);
DISPLAY INVISIBLE (-1790 4010);
FORCEPROP 1 LASTPIN (-1800 4000) BN 44
J 2
(-1750 4010);
DISPLAY 0.617021 (-1750 4010);
PAINT PINK (-1750 4010);
FORCEPROP 2 LAST CDS_LIB mstr_standard
J 2
(-1750 4000);
DISPLAY 0.787234 (-1750 4000);
PAINT MONO (-1750 4000);
DISPLAY INVISIBLE (-1750 4000);
FORCEPROP 1 LAST BODY_TYPE PLUMBING
J 2
(-1750 3950);
DISPLAY 1.234043 (-1750 3950);
PAINT GREEN (-1750 3950);
DISPLAY INVISIBLE (-1750 3950);
FORCEPROP 1 LAST HDL_TAP TRUE
J 2
(-2075 3875);
DISPLAY 1.234043 (-2075 3875);
PAINT GREEN (-2075 3875);
DISPLAY INVISIBLE (-2075 3875);
FORCEPROP 1 LAST PATH I61
J 2
(-1750 4000);
DISPLAY 0.936170 (-1750 4000);
PAINT GREEN (-1750 4000);
DISPLAY INVISIBLE (-1750 4000);
FORCEADD TAP..6
R 2
(-1750 4050);
FORCEPROP 3 LASTPIN (-1800 4050) SIG_NAME M_L_DQ<47>
J 0
(-1790 4060);
DISPLAY 0.659574 (-1790 4060);
PAINT MONO (-1790 4060);
DISPLAY INVISIBLE (-1790 4060);
FORCEPROP 1 LASTPIN (-1800 4050) BN 47
J 2
(-1750 4060);
DISPLAY 0.617021 (-1750 4060);
PAINT PINK (-1750 4060);
FORCEPROP 2 LAST CDS_LIB mstr_standard
J 2
(-1750 4050);
DISPLAY 0.787234 (-1750 4050);
PAINT MONO (-1750 4050);
DISPLAY INVISIBLE (-1750 4050);
FORCEPROP 1 LAST BODY_TYPE PLUMBING
J 2
(-1750 4000);
DISPLAY 1.234043 (-1750 4000);
PAINT GREEN (-1750 4000);
DISPLAY INVISIBLE (-1750 4000);
FORCEPROP 1 LAST HDL_TAP TRUE
J 2
(-2075 3925);
DISPLAY 1.234043 (-2075 3925);
PAINT GREEN (-2075 3925);
DISPLAY INVISIBLE (-2075 3925);
FORCEPROP 1 LAST PATH I62
J 2
(-1750 4050);
DISPLAY 0.936170 (-1750 4050);
PAINT GREEN (-1750 4050);
DISPLAY INVISIBLE (-1750 4050);
FORCEADD TAP..6
R 2
(-1750 4150);
FORCEPROP 3 LASTPIN (-1800 4150) SIG_NAME M_L_DQ<49>
J 0
(-1790 4160);
DISPLAY 0.659574 (-1790 4160);
PAINT MONO (-1790 4160);
DISPLAY INVISIBLE (-1790 4160);
FORCEPROP 1 LASTPIN (-1800 4150) BN 49
J 2
(-1750 4160);
DISPLAY 0.617021 (-1750 4160);
PAINT PINK (-1750 4160);
FORCEPROP 2 LAST CDS_LIB mstr_standard
J 2
(-1750 4150);
DISPLAY 0.787234 (-1750 4150);
PAINT MONO (-1750 4150);
DISPLAY INVISIBLE (-1750 4150);
FORCEPROP 1 LAST BODY_TYPE PLUMBING
J 2
(-1750 4100);
DISPLAY 1.234043 (-1750 4100);
PAINT GREEN (-1750 4100);
DISPLAY INVISIBLE (-1750 4100);
FORCEPROP 1 LAST HDL_TAP TRUE
J 2
(-2075 4025);
DISPLAY 1.234043 (-2075 4025);
PAINT GREEN (-2075 4025);
DISPLAY INVISIBLE (-2075 4025);
FORCEPROP 1 LAST PATH I63
J 2
(-1750 4150);
DISPLAY 0.936170 (-1750 4150);
PAINT GREEN (-1750 4150);
DISPLAY INVISIBLE (-1750 4150);
FORCEADD TAP..6
R 2
(-1750 4100);
FORCEPROP 3 LASTPIN (-1800 4100) SIG_NAME M_L_DQ<46>
J 0
(-1790 4110);
DISPLAY 0.659574 (-1790 4110);
PAINT MONO (-1790 4110);
DISPLAY INVISIBLE (-1790 4110);
FORCEPROP 1 LASTPIN (-1800 4100) BN 46
J 2
(-1750 4110);
DISPLAY 0.617021 (-1750 4110);
PAINT PINK (-1750 4110);
FORCEPROP 2 LAST CDS_LIB mstr_standard
J 2
(-1750 4100);
DISPLAY 0.787234 (-1750 4100);
PAINT MONO (-1750 4100);
DISPLAY INVISIBLE (-1750 4100);
FORCEPROP 1 LAST BODY_TYPE PLUMBING
J 2
(-1750 4050);
DISPLAY 1.234043 (-1750 4050);
PAINT GREEN (-1750 4050);
DISPLAY INVISIBLE (-1750 4050);
FORCEPROP 1 LAST HDL_TAP TRUE
J 2
(-2075 3975);
DISPLAY 1.234043 (-2075 3975);
PAINT GREEN (-2075 3975);
DISPLAY INVISIBLE (-2075 3975);
FORCEPROP 1 LAST PATH I64
J 2
(-1750 4100);
DISPLAY 0.936170 (-1750 4100);
PAINT GREEN (-1750 4100);
DISPLAY INVISIBLE (-1750 4100);
FORCEADD TAP..6
R 2
(-1750 4200);
FORCEPROP 3 LASTPIN (-1800 4200) SIG_NAME M_L_DQ<48>
J 0
(-1790 4210);
DISPLAY 0.659574 (-1790 4210);
PAINT MONO (-1790 4210);
DISPLAY INVISIBLE (-1790 4210);
FORCEPROP 1 LASTPIN (-1800 4200) BN 48
J 2
(-1750 4210);
DISPLAY 0.617021 (-1750 4210);
PAINT PINK (-1750 4210);
FORCEPROP 2 LAST CDS_LIB mstr_standard
J 2
(-1750 4200);
DISPLAY 0.787234 (-1750 4200);
PAINT MONO (-1750 4200);
DISPLAY INVISIBLE (-1750 4200);
FORCEPROP 1 LAST BODY_TYPE PLUMBING
J 2
(-1750 4150);
DISPLAY 1.234043 (-1750 4150);
PAINT GREEN (-1750 4150);
DISPLAY INVISIBLE (-1750 4150);
FORCEPROP 1 LAST HDL_TAP TRUE
J 2
(-2075 4075);
DISPLAY 1.234043 (-2075 4075);
PAINT GREEN (-2075 4075);
DISPLAY INVISIBLE (-2075 4075);
FORCEPROP 1 LAST PATH I65
J 2
(-1750 4200);
DISPLAY 0.936170 (-1750 4200);
PAINT GREEN (-1750 4200);
DISPLAY INVISIBLE (-1750 4200);
FORCEADD SCONN288_H44441004..2
(0 4300);
FORCEPROP 1 LAST LOCATION J1A2
J 0
(-400 5400);
DISPLAY 0.617021 (-400 5400);
PAINT AQUA (-400 5400);
FORCEPROP 1 LAST PART_NUMBER H44441-004
J 0
(-400 3200);
DISPLAY 0.617021 (-400 3200);
PAINT BLUE (-400 3200);
FORCEPROP 1 LAST MATERIAL SCONN
J 0
(-400 5350);
DISPLAY 0.617021 (-400 5350);
PAINT SKYBLUE (-400 5350);
FORCEPROP 2 LASTPIN (450 5150) $PN 51
J 0
(460 5160);
DISPLAY 0.617021 (460 5160);
PAINT ORANGE (460 5160);
FORCEPROP 2 LASTPIN (450 5100) $PN 52
J 0
(460 5110);
DISPLAY 0.617021 (460 5110);
PAINT ORANGE (460 5110);
FORCEPROP 2 LASTPIN (450 5050) $PN 132
J 0
(460 5060);
DISPLAY 0.617021 (460 5060);
PAINT ORANGE (460 5060);
FORCEPROP 2 LASTPIN (450 5000) $PN 133
J 0
(460 5010);
DISPLAY 0.617021 (460 5010);
PAINT ORANGE (460 5010);
FORCEPROP 2 LASTPIN (450 4950) $PN 121
J 0
(460 4960);
DISPLAY 0.617021 (460 4960);
PAINT ORANGE (460 4960);
FORCEPROP 2 LASTPIN (450 4900) $PN 122
J 0
(460 4910);
DISPLAY 0.617021 (460 4910);
PAINT ORANGE (460 4910);
FORCEPROP 2 LASTPIN (450 4850) $PN 110
J 0
(460 4860);
DISPLAY 0.617021 (460 4860);
PAINT ORANGE (460 4860);
FORCEPROP 2 LASTPIN (450 4800) $PN 111
J 0
(460 4810);
DISPLAY 0.617021 (460 4810);
PAINT ORANGE (460 4810);
FORCEPROP 2 LASTPIN (450 4750) $PN 99
J 0
(460 4760);
DISPLAY 0.617021 (460 4760);
PAINT ORANGE (460 4760);
FORCEPROP 2 LASTPIN (450 4700) $PN 100
J 0
(460 4710);
DISPLAY 0.617021 (460 4710);
PAINT ORANGE (460 4710);
FORCEPROP 2 LASTPIN (450 4650) $PN 40
J 0
(460 4660);
DISPLAY 0.617021 (460 4660);
PAINT ORANGE (460 4660);
FORCEPROP 2 LASTPIN (450 4600) $PN 41
J 0
(460 4610);
DISPLAY 0.617021 (460 4610);
PAINT ORANGE (460 4610);
FORCEPROP 2 LASTPIN (450 4550) $PN 29
J 0
(460 4560);
DISPLAY 0.617021 (460 4560);
PAINT ORANGE (460 4560);
FORCEPROP 2 LASTPIN (450 4500) $PN 30
J 0
(460 4510);
DISPLAY 0.617021 (460 4510);
PAINT ORANGE (460 4510);
FORCEPROP 2 LASTPIN (450 4450) $PN 18
J 0
(460 4460);
DISPLAY 0.617021 (460 4460);
PAINT ORANGE (460 4460);
FORCEPROP 2 LASTPIN (450 4400) $PN 19
J 0
(460 4410);
DISPLAY 0.617021 (460 4410);
PAINT ORANGE (460 4410);
FORCEPROP 2 LASTPIN (450 4350) $PN 7
J 0
(460 4360);
DISPLAY 0.617021 (460 4360);
PAINT ORANGE (460 4360);
FORCEPROP 2 LASTPIN (450 4300) $PN 8
J 0
(460 4310);
DISPLAY 0.617021 (460 4310);
PAINT ORANGE (460 4310);
FORCEPROP 2 LASTPIN (450 4250) $PN 197
J 0
(460 4260);
DISPLAY 0.617021 (460 4260);
PAINT ORANGE (460 4260);
FORCEPROP 2 LASTPIN (450 4200) $PN 196
J 0
(460 4210);
DISPLAY 0.617021 (460 4210);
PAINT ORANGE (460 4210);
FORCEPROP 2 LASTPIN (450 4150) $PN 278
J 0
(460 4160);
DISPLAY 0.617021 (460 4160);
PAINT ORANGE (460 4160);
FORCEPROP 2 LASTPIN (450 4100) $PN 277
J 0
(460 4110);
DISPLAY 0.617021 (460 4110);
PAINT ORANGE (460 4110);
FORCEPROP 2 LASTPIN (450 4050) $PN 267
J 0
(460 4060);
DISPLAY 0.617021 (460 4060);
PAINT ORANGE (460 4060);
FORCEPROP 2 LASTPIN (450 4000) $PN 266
J 0
(460 4010);
DISPLAY 0.617021 (460 4010);
PAINT ORANGE (460 4010);
FORCEPROP 2 LASTPIN (450 3950) $PN 256
J 0
(460 3960);
DISPLAY 0.617021 (460 3960);
PAINT ORANGE (460 3960);
FORCEPROP 2 LASTPIN (450 3900) $PN 255
J 0
(460 3910);
DISPLAY 0.617021 (460 3910);
PAINT ORANGE (460 3910);
FORCEPROP 2 LASTPIN (450 3850) $PN 245
J 0
(460 3860);
DISPLAY 0.617021 (460 3860);
PAINT ORANGE (460 3860);
FORCEPROP 2 LASTPIN (450 3800) $PN 244
J 0
(460 3810);
DISPLAY 0.617021 (460 3810);
PAINT ORANGE (460 3810);
FORCEPROP 2 LASTPIN (450 3750) $PN 186
J 0
(460 3760);
DISPLAY 0.617021 (460 3760);
PAINT ORANGE (460 3760);
FORCEPROP 2 LASTPIN (450 3650) $PN 175
J 0
(460 3660);
DISPLAY 0.617021 (460 3660);
PAINT ORANGE (460 3660);
FORCEPROP 2 LASTPIN (450 3600) $PN 174
J 0
(460 3610);
DISPLAY 0.617021 (460 3610);
PAINT ORANGE (460 3610);
FORCEPROP 2 LASTPIN (450 3550) $PN 164
J 0
(460 3560);
DISPLAY 0.617021 (460 3560);
PAINT ORANGE (460 3560);
FORCEPROP 2 LASTPIN (450 3500) $PN 163
J 0
(460 3510);
DISPLAY 0.617021 (460 3510);
PAINT ORANGE (460 3510);
FORCEPROP 2 LASTPIN (450 3450) $PN 153
J 0
(460 3460);
DISPLAY 0.617021 (460 3460);
PAINT ORANGE (460 3460);
FORCEPROP 2 LASTPIN (450 3400) $PN 152
J 0
(460 3410);
DISPLAY 0.617021 (460 3410);
PAINT ORANGE (460 3410);
FORCEPROP 2 LASTPIN (450 3700) $PN 185
J 0
(460 3710);
DISPLAY 0.617021 (460 3710);
PAINT ORANGE (460 3710);
FORCEPROP 1 LAST PACK_TYPE PIP
J 0
(-400 5450);
PAINT SKYBLUE (-400 5450);
DISPLAY INVISIBLE (-400 5450);
FORCEPROP 2 LAST BOM_COST MEM
J 0
(0 4300);
PAINT ORANGE (0 4300);
DISPLAY INVISIBLE (0 4300);
FORCEPROP 2 LAST CDS_LIB mstr_sconn
J 0
(0 4300);
PAINT ORANGE (0 4300);
DISPLAY INVISIBLE (0 4300);
FORCEPROP 2 LAST SEC_TYPE PIP
J 0
(-400 5450);
DISPLAY 1.021277 (-400 5450);
PAINT ORANGE (-400 5450);
DISPLAY INVISIBLE (-400 5450);
FORCEPROP 2 LAST SEC 2
J 0
(-400 5450);
DISPLAY 0.680851 (-400 5450);
PAINT MONO (-400 5450);
DISPLAY INVISIBLE (-400 5450);
FORCEPROP 2 LAST CDS_LOCATION J1A2
J 0
(-400 5400);
DISPLAY 0.617021 (-400 5400);
PAINT AQUA (-400 5400);
DISPLAY INVISIBLE (-400 5400);
FORCEPROP 1 LAST PATH I66
J 0
(0 5350);
PAINT GREEN (0 5350);
DISPLAY INVISIBLE (0 5350);
FORCEPROP 2 LAST ROOM DDR4_CH_L
J 0
(-400 5500);
PAINT ORANGE (-400 5500);
DISPLAY INVISIBLE (-400 5500);
FORCEADD TAP..6
R 2
(-1750 3800);
FORCEPROP 3 LASTPIN (-1800 3800) SIG_NAME M_L_DQ<40>
J 0
(-1790 3810);
DISPLAY 0.659574 (-1790 3810);
PAINT MONO (-1790 3810);
DISPLAY INVISIBLE (-1790 3810);
FORCEPROP 1 LASTPIN (-1800 3800) BN 40
J 2
(-1750 3810);
DISPLAY 0.617021 (-1750 3810);
PAINT PINK (-1750 3810);
FORCEPROP 2 LAST CDS_LIB mstr_standard
J 2
(-1750 3800);
DISPLAY 0.787234 (-1750 3800);
PAINT MONO (-1750 3800);
DISPLAY INVISIBLE (-1750 3800);
FORCEPROP 1 LAST BODY_TYPE PLUMBING
J 2
(-1750 3750);
DISPLAY 1.234043 (-1750 3750);
PAINT GREEN (-1750 3750);
DISPLAY INVISIBLE (-1750 3750);
FORCEPROP 1 LAST HDL_TAP TRUE
J 2
(-2075 3675);
DISPLAY 1.234043 (-2075 3675);
PAINT GREEN (-2075 3675);
DISPLAY INVISIBLE (-2075 3675);
FORCEPROP 1 LAST PATH I67
J 2
(-1750 3800);
DISPLAY 0.936170 (-1750 3800);
PAINT GREEN (-1750 3800);
DISPLAY INVISIBLE (-1750 3800);
FORCEADD TAP..6
R 2
(-1750 3700);
FORCEPROP 3 LASTPIN (-1800 3700) SIG_NAME M_L_DQ<38>
J 0
(-1790 3710);
DISPLAY 0.659574 (-1790 3710);
PAINT MONO (-1790 3710);
DISPLAY INVISIBLE (-1790 3710);
FORCEPROP 1 LASTPIN (-1800 3700) BN 38
J 2
(-1750 3710);
DISPLAY 0.617021 (-1750 3710);
PAINT PINK (-1750 3710);
FORCEPROP 2 LAST CDS_LIB mstr_standard
J 2
(-1750 3700);
DISPLAY 0.787234 (-1750 3700);
PAINT MONO (-1750 3700);
DISPLAY INVISIBLE (-1750 3700);
FORCEPROP 1 LAST BODY_TYPE PLUMBING
J 2
(-1750 3650);
DISPLAY 1.234043 (-1750 3650);
PAINT GREEN (-1750 3650);
DISPLAY INVISIBLE (-1750 3650);
FORCEPROP 1 LAST HDL_TAP TRUE
J 2
(-2075 3575);
DISPLAY 1.234043 (-2075 3575);
PAINT GREEN (-2075 3575);
DISPLAY INVISIBLE (-2075 3575);
FORCEPROP 1 LAST PATH I68
J 2
(-1750 3700);
DISPLAY 0.936170 (-1750 3700);
PAINT GREEN (-1750 3700);
DISPLAY INVISIBLE (-1750 3700);
FORCEADD TAP..6
R 2
(-1750 3750);
FORCEPROP 3 LASTPIN (-1800 3750) SIG_NAME M_L_DQ<41>
J 0
(-1790 3760);
DISPLAY 0.659574 (-1790 3760);
PAINT MONO (-1790 3760);
DISPLAY INVISIBLE (-1790 3760);
FORCEPROP 1 LASTPIN (-1800 3750) BN 41
J 2
(-1750 3760);
DISPLAY 0.617021 (-1750 3760);
PAINT PINK (-1750 3760);
FORCEPROP 2 LAST CDS_LIB mstr_standard
J 2
(-1750 3750);
DISPLAY 0.787234 (-1750 3750);
PAINT MONO (-1750 3750);
DISPLAY INVISIBLE (-1750 3750);
FORCEPROP 1 LAST BODY_TYPE PLUMBING
J 2
(-1750 3700);
DISPLAY 1.234043 (-1750 3700);
PAINT GREEN (-1750 3700);
DISPLAY INVISIBLE (-1750 3700);
FORCEPROP 1 LAST HDL_TAP TRUE
J 2
(-2075 3625);
DISPLAY 1.234043 (-2075 3625);
PAINT GREEN (-2075 3625);
DISPLAY INVISIBLE (-2075 3625);
FORCEPROP 1 LAST PATH I69
J 2
(-1750 3750);
DISPLAY 0.936170 (-1750 3750);
PAINT GREEN (-1750 3750);
DISPLAY INVISIBLE (-1750 3750);
FORCEADD TAP..6
R 2
(900 4800);
FORCEPROP 3 LASTPIN (850 4800) SIG_NAME M_L_DQS_DN<14>
J 0
(860 4810);
DISPLAY 0.659574 (860 4810);
PAINT MONO (860 4810);
DISPLAY INVISIBLE (860 4810);
FORCEPROP 1 LASTPIN (850 4800) BN 14
J 2
(900 4810);
DISPLAY 0.617021 (900 4810);
PAINT PINK (900 4810);
FORCEPROP 2 LAST CDS_LIB mstr_standard
J 0
(900 4800);
DISPLAY 0.787234 (900 4800);
PAINT MONO (900 4800);
DISPLAY INVISIBLE (900 4800);
FORCEPROP 1 LAST BODY_TYPE PLUMBING
J 2
(900 4750);
DISPLAY 1.234043 (900 4750);
PAINT GREEN (900 4750);
DISPLAY INVISIBLE (900 4750);
FORCEPROP 1 LAST HDL_TAP TRUE
J 2
(575 4675);
DISPLAY 1.234043 (575 4675);
PAINT GREEN (575 4675);
DISPLAY INVISIBLE (575 4675);
FORCEPROP 1 LAST PATH I7
J 2
(900 4800);
DISPLAY 0.936170 (900 4800);
PAINT GREEN (900 4800);
DISPLAY INVISIBLE (900 4800);
FORCEADD TAP..6
R 2
(-1750 3850);
FORCEPROP 3 LASTPIN (-1800 3850) SIG_NAME M_L_DQ<43>
J 0
(-1790 3860);
DISPLAY 0.659574 (-1790 3860);
PAINT MONO (-1790 3860);
DISPLAY INVISIBLE (-1790 3860);
FORCEPROP 1 LASTPIN (-1800 3850) BN 43
J 2
(-1750 3860);
DISPLAY 0.617021 (-1750 3860);
PAINT PINK (-1750 3860);
FORCEPROP 2 LAST CDS_LIB mstr_standard
J 2
(-1750 3850);
DISPLAY 0.787234 (-1750 3850);
PAINT MONO (-1750 3850);
DISPLAY INVISIBLE (-1750 3850);
FORCEPROP 1 LAST BODY_TYPE PLUMBING
J 2
(-1750 3800);
DISPLAY 1.234043 (-1750 3800);
PAINT GREEN (-1750 3800);
DISPLAY INVISIBLE (-1750 3800);
FORCEPROP 1 LAST HDL_TAP TRUE
J 2
(-2075 3725);
DISPLAY 1.234043 (-2075 3725);
PAINT GREEN (-2075 3725);
DISPLAY INVISIBLE (-2075 3725);
FORCEPROP 1 LAST PATH I70
J 2
(-1750 3850);
DISPLAY 0.936170 (-1750 3850);
PAINT GREEN (-1750 3850);
DISPLAY INVISIBLE (-1750 3850);
FORCEADD TAP..6
R 2
(-1750 3900);
FORCEPROP 3 LASTPIN (-1800 3900) SIG_NAME M_L_DQ<42>
J 0
(-1790 3910);
DISPLAY 0.659574 (-1790 3910);
PAINT MONO (-1790 3910);
DISPLAY INVISIBLE (-1790 3910);
FORCEPROP 1 LASTPIN (-1800 3900) BN 42
J 2
(-1750 3910);
DISPLAY 0.617021 (-1750 3910);
PAINT PINK (-1750 3910);
FORCEPROP 2 LAST CDS_LIB mstr_standard
J 2
(-1750 3900);
DISPLAY 0.787234 (-1750 3900);
PAINT MONO (-1750 3900);
DISPLAY INVISIBLE (-1750 3900);
FORCEPROP 1 LAST BODY_TYPE PLUMBING
J 2
(-1750 3850);
DISPLAY 1.234043 (-1750 3850);
PAINT GREEN (-1750 3850);
DISPLAY INVISIBLE (-1750 3850);
FORCEPROP 1 LAST HDL_TAP TRUE
J 2
(-2075 3775);
DISPLAY 1.234043 (-2075 3775);
PAINT GREEN (-2075 3775);
DISPLAY INVISIBLE (-2075 3775);
FORCEPROP 1 LAST PATH I71
J 2
(-1750 3900);
DISPLAY 0.936170 (-1750 3900);
PAINT GREEN (-1750 3900);
DISPLAY INVISIBLE (-1750 3900);
FORCEADD TAP..6
R 2
(-1750 3500);
FORCEPROP 3 LASTPIN (-1800 3500) SIG_NAME M_L_DQ<34>
J 0
(-1790 3510);
DISPLAY 0.659574 (-1790 3510);
PAINT MONO (-1790 3510);
DISPLAY INVISIBLE (-1790 3510);
FORCEPROP 1 LASTPIN (-1800 3500) BN 34
J 2
(-1750 3510);
DISPLAY 0.617021 (-1750 3510);
PAINT PINK (-1750 3510);
FORCEPROP 2 LAST CDS_LIB mstr_standard
J 2
(-1750 3500);
DISPLAY 0.787234 (-1750 3500);
PAINT MONO (-1750 3500);
DISPLAY INVISIBLE (-1750 3500);
FORCEPROP 1 LAST BODY_TYPE PLUMBING
J 2
(-1750 3450);
DISPLAY 1.234043 (-1750 3450);
PAINT GREEN (-1750 3450);
DISPLAY INVISIBLE (-1750 3450);
FORCEPROP 1 LAST HDL_TAP TRUE
J 2
(-2075 3375);
DISPLAY 1.234043 (-2075 3375);
PAINT GREEN (-2075 3375);
DISPLAY INVISIBLE (-2075 3375);
FORCEPROP 1 LAST PATH I72
J 2
(-1750 3500);
DISPLAY 0.936170 (-1750 3500);
PAINT GREEN (-1750 3500);
DISPLAY INVISIBLE (-1750 3500);
FORCEADD TAP..6
R 2
(-1750 3450);
FORCEPROP 3 LASTPIN (-1800 3450) SIG_NAME M_L_DQ<35>
J 0
(-1790 3460);
DISPLAY 0.659574 (-1790 3460);
PAINT MONO (-1790 3460);
DISPLAY INVISIBLE (-1790 3460);
FORCEPROP 1 LASTPIN (-1800 3450) BN 35
J 2
(-1750 3460);
DISPLAY 0.617021 (-1750 3460);
PAINT PINK (-1750 3460);
FORCEPROP 2 LAST CDS_LIB mstr_standard
J 2
(-1750 3450);
DISPLAY 0.787234 (-1750 3450);
PAINT MONO (-1750 3450);
DISPLAY INVISIBLE (-1750 3450);
FORCEPROP 1 LAST BODY_TYPE PLUMBING
J 2
(-1750 3400);
DISPLAY 1.234043 (-1750 3400);
PAINT GREEN (-1750 3400);
DISPLAY INVISIBLE (-1750 3400);
FORCEPROP 1 LAST HDL_TAP TRUE
J 2
(-2075 3325);
DISPLAY 1.234043 (-2075 3325);
PAINT GREEN (-2075 3325);
DISPLAY INVISIBLE (-2075 3325);
FORCEPROP 1 LAST PATH I73
J 2
(-1750 3450);
DISPLAY 0.936170 (-1750 3450);
PAINT GREEN (-1750 3450);
DISPLAY INVISIBLE (-1750 3450);
FORCEADD TAP..6
R 2
(-1750 3550);
FORCEPROP 3 LASTPIN (-1800 3550) SIG_NAME M_L_DQ<37>
J 0
(-1790 3560);
DISPLAY 0.659574 (-1790 3560);
PAINT MONO (-1790 3560);
DISPLAY INVISIBLE (-1790 3560);
FORCEPROP 1 LASTPIN (-1800 3550) BN 37
J 2
(-1750 3560);
DISPLAY 0.617021 (-1750 3560);
PAINT PINK (-1750 3560);
FORCEPROP 2 LAST CDS_LIB mstr_standard
J 2
(-1750 3550);
DISPLAY 0.787234 (-1750 3550);
PAINT MONO (-1750 3550);
DISPLAY INVISIBLE (-1750 3550);
FORCEPROP 1 LAST BODY_TYPE PLUMBING
J 2
(-1750 3500);
DISPLAY 1.234043 (-1750 3500);
PAINT GREEN (-1750 3500);
DISPLAY INVISIBLE (-1750 3500);
FORCEPROP 1 LAST HDL_TAP TRUE
J 2
(-2075 3425);
DISPLAY 1.234043 (-2075 3425);
PAINT GREEN (-2075 3425);
DISPLAY INVISIBLE (-2075 3425);
FORCEPROP 1 LAST PATH I74
J 2
(-1750 3550);
DISPLAY 0.936170 (-1750 3550);
PAINT GREEN (-1750 3550);
DISPLAY INVISIBLE (-1750 3550);
FORCEADD TAP..6
R 2
(-1750 3600);
FORCEPROP 3 LASTPIN (-1800 3600) SIG_NAME M_L_DQ<36>
J 0
(-1790 3610);
DISPLAY 0.659574 (-1790 3610);
PAINT MONO (-1790 3610);
DISPLAY INVISIBLE (-1790 3610);
FORCEPROP 1 LASTPIN (-1800 3600) BN 36
J 2
(-1750 3610);
DISPLAY 0.617021 (-1750 3610);
PAINT PINK (-1750 3610);
FORCEPROP 2 LAST CDS_LIB mstr_standard
J 2
(-1750 3600);
DISPLAY 0.787234 (-1750 3600);
PAINT MONO (-1750 3600);
DISPLAY INVISIBLE (-1750 3600);
FORCEPROP 1 LAST BODY_TYPE PLUMBING
J 2
(-1750 3550);
DISPLAY 1.234043 (-1750 3550);
PAINT GREEN (-1750 3550);
DISPLAY INVISIBLE (-1750 3550);
FORCEPROP 1 LAST HDL_TAP TRUE
J 2
(-2075 3475);
DISPLAY 1.234043 (-2075 3475);
PAINT GREEN (-2075 3475);
DISPLAY INVISIBLE (-2075 3475);
FORCEPROP 1 LAST PATH I75
J 2
(-1750 3600);
DISPLAY 0.936170 (-1750 3600);
PAINT GREEN (-1750 3600);
DISPLAY INVISIBLE (-1750 3600);
FORCEADD TAP..6
R 2
(-1750 3650);
FORCEPROP 3 LASTPIN (-1800 3650) SIG_NAME M_L_DQ<39>
J 0
(-1790 3660);
DISPLAY 0.659574 (-1790 3660);
PAINT MONO (-1790 3660);
DISPLAY INVISIBLE (-1790 3660);
FORCEPROP 1 LASTPIN (-1800 3650) BN 39
J 2
(-1750 3660);
DISPLAY 0.617021 (-1750 3660);
PAINT PINK (-1750 3660);
FORCEPROP 2 LAST CDS_LIB mstr_standard
J 2
(-1750 3650);
DISPLAY 0.787234 (-1750 3650);
PAINT MONO (-1750 3650);
DISPLAY INVISIBLE (-1750 3650);
FORCEPROP 1 LAST BODY_TYPE PLUMBING
J 2
(-1750 3600);
DISPLAY 1.234043 (-1750 3600);
PAINT GREEN (-1750 3600);
DISPLAY INVISIBLE (-1750 3600);
FORCEPROP 1 LAST HDL_TAP TRUE
J 2
(-2075 3525);
DISPLAY 1.234043 (-2075 3525);
PAINT GREEN (-2075 3525);
DISPLAY INVISIBLE (-2075 3525);
FORCEPROP 1 LAST PATH I76
J 2
(-1750 3650);
DISPLAY 0.936170 (-1750 3650);
PAINT GREEN (-1750 3650);
DISPLAY INVISIBLE (-1750 3650);
FORCEADD TAP..6
R 2
(-1750 3250);
FORCEPROP 3 LASTPIN (-1800 3250) SIG_NAME M_L_DQ<31>
J 0
(-1790 3260);
DISPLAY 0.659574 (-1790 3260);
PAINT MONO (-1790 3260);
DISPLAY INVISIBLE (-1790 3260);
FORCEPROP 1 LASTPIN (-1800 3250) BN 31
J 2
(-1750 3260);
DISPLAY 0.617021 (-1750 3260);
PAINT PINK (-1750 3260);
FORCEPROP 2 LAST CDS_LIB mstr_standard
J 2
(-1750 3250);
DISPLAY 0.787234 (-1750 3250);
PAINT MONO (-1750 3250);
DISPLAY INVISIBLE (-1750 3250);
FORCEPROP 1 LAST BODY_TYPE PLUMBING
J 2
(-1750 3200);
DISPLAY 1.234043 (-1750 3200);
PAINT GREEN (-1750 3200);
DISPLAY INVISIBLE (-1750 3200);
FORCEPROP 1 LAST HDL_TAP TRUE
J 2
(-2075 3125);
DISPLAY 1.234043 (-2075 3125);
PAINT GREEN (-2075 3125);
DISPLAY INVISIBLE (-2075 3125);
FORCEPROP 1 LAST PATH I77
J 2
(-1750 3250);
DISPLAY 0.936170 (-1750 3250);
PAINT GREEN (-1750 3250);
DISPLAY INVISIBLE (-1750 3250);
FORCEADD TAP..6
R 2
(-1750 3300);
FORCEPROP 3 LASTPIN (-1800 3300) SIG_NAME M_L_DQ<30>
J 0
(-1790 3310);
DISPLAY 0.659574 (-1790 3310);
PAINT MONO (-1790 3310);
DISPLAY INVISIBLE (-1790 3310);
FORCEPROP 1 LASTPIN (-1800 3300) BN 30
J 2
(-1750 3310);
DISPLAY 0.617021 (-1750 3310);
PAINT PINK (-1750 3310);
FORCEPROP 2 LAST CDS_LIB mstr_standard
J 2
(-1750 3300);
DISPLAY 0.787234 (-1750 3300);
PAINT MONO (-1750 3300);
DISPLAY INVISIBLE (-1750 3300);
FORCEPROP 1 LAST BODY_TYPE PLUMBING
J 2
(-1750 3250);
DISPLAY 1.234043 (-1750 3250);
PAINT GREEN (-1750 3250);
DISPLAY INVISIBLE (-1750 3250);
FORCEPROP 1 LAST HDL_TAP TRUE
J 2
(-2075 3175);
DISPLAY 1.234043 (-2075 3175);
PAINT GREEN (-2075 3175);
DISPLAY INVISIBLE (-2075 3175);
FORCEPROP 1 LAST PATH I78
J 2
(-1750 3300);
DISPLAY 0.936170 (-1750 3300);
PAINT GREEN (-1750 3300);
DISPLAY INVISIBLE (-1750 3300);
FORCEADD TAP..6
R 2
(-1750 3200);
FORCEPROP 3 LASTPIN (-1800 3200) SIG_NAME M_L_DQ<28>
J 0
(-1790 3210);
DISPLAY 0.659574 (-1790 3210);
PAINT MONO (-1790 3210);
DISPLAY INVISIBLE (-1790 3210);
FORCEPROP 1 LASTPIN (-1800 3200) BN 28
J 2
(-1750 3210);
DISPLAY 0.617021 (-1750 3210);
PAINT PINK (-1750 3210);
FORCEPROP 2 LAST CDS_LIB mstr_standard
J 2
(-1750 3200);
DISPLAY 0.787234 (-1750 3200);
PAINT MONO (-1750 3200);
DISPLAY INVISIBLE (-1750 3200);
FORCEPROP 1 LAST BODY_TYPE PLUMBING
J 2
(-1750 3150);
DISPLAY 1.234043 (-1750 3150);
PAINT GREEN (-1750 3150);
DISPLAY INVISIBLE (-1750 3150);
FORCEPROP 1 LAST HDL_TAP TRUE
J 2
(-2075 3075);
DISPLAY 1.234043 (-2075 3075);
PAINT GREEN (-2075 3075);
DISPLAY INVISIBLE (-2075 3075);
FORCEPROP 1 LAST PATH I79
J 2
(-1750 3200);
DISPLAY 0.936170 (-1750 3200);
PAINT GREEN (-1750 3200);
DISPLAY INVISIBLE (-1750 3200);
FORCEADD TAP..6
R 2
(900 4700);
FORCEPROP 3 LASTPIN (850 4700) SIG_NAME M_L_DQS_DN<13>
J 0
(860 4710);
DISPLAY 0.659574 (860 4710);
PAINT MONO (860 4710);
DISPLAY INVISIBLE (860 4710);
FORCEPROP 1 LASTPIN (850 4700) BN 13
J 2
(900 4710);
DISPLAY 0.617021 (900 4710);
PAINT PINK (900 4710);
FORCEPROP 2 LAST CDS_LIB mstr_standard
J 0
(900 4700);
DISPLAY 0.787234 (900 4700);
PAINT MONO (900 4700);
DISPLAY INVISIBLE (900 4700);
FORCEPROP 1 LAST BODY_TYPE PLUMBING
J 2
(900 4650);
DISPLAY 1.234043 (900 4650);
PAINT GREEN (900 4650);
DISPLAY INVISIBLE (900 4650);
FORCEPROP 1 LAST HDL_TAP TRUE
J 2
(575 4575);
DISPLAY 1.234043 (575 4575);
PAINT GREEN (575 4575);
DISPLAY INVISIBLE (575 4575);
FORCEPROP 1 LAST PATH I8
J 2
(900 4700);
DISPLAY 0.936170 (900 4700);
PAINT GREEN (900 4700);
DISPLAY INVISIBLE (900 4700);
FORCEADD TAP..6
R 2
(-1750 3350);
FORCEPROP 3 LASTPIN (-1800 3350) SIG_NAME M_L_DQ<33>
J 0
(-1790 3360);
DISPLAY 0.659574 (-1790 3360);
PAINT MONO (-1790 3360);
DISPLAY INVISIBLE (-1790 3360);
FORCEPROP 1 LASTPIN (-1800 3350) BN 33
J 2
(-1750 3360);
DISPLAY 0.617021 (-1750 3360);
PAINT PINK (-1750 3360);
FORCEPROP 2 LAST CDS_LIB mstr_standard
J 2
(-1750 3350);
DISPLAY 0.787234 (-1750 3350);
PAINT MONO (-1750 3350);
DISPLAY INVISIBLE (-1750 3350);
FORCEPROP 1 LAST BODY_TYPE PLUMBING
J 2
(-1750 3300);
DISPLAY 1.234043 (-1750 3300);
PAINT GREEN (-1750 3300);
DISPLAY INVISIBLE (-1750 3300);
FORCEPROP 1 LAST HDL_TAP TRUE
J 2
(-2075 3225);
DISPLAY 1.234043 (-2075 3225);
PAINT GREEN (-2075 3225);
DISPLAY INVISIBLE (-2075 3225);
FORCEPROP 1 LAST PATH I80
J 2
(-1750 3350);
DISPLAY 0.936170 (-1750 3350);
PAINT GREEN (-1750 3350);
DISPLAY INVISIBLE (-1750 3350);
FORCEADD TAP..6
R 2
(-1750 3400);
FORCEPROP 3 LASTPIN (-1800 3400) SIG_NAME M_L_DQ<32>
J 0
(-1790 3410);
DISPLAY 0.659574 (-1790 3410);
PAINT MONO (-1790 3410);
DISPLAY INVISIBLE (-1790 3410);
FORCEPROP 1 LASTPIN (-1800 3400) BN 32
J 2
(-1750 3410);
DISPLAY 0.617021 (-1750 3410);
PAINT PINK (-1750 3410);
FORCEPROP 2 LAST CDS_LIB mstr_standard
J 2
(-1750 3400);
DISPLAY 0.787234 (-1750 3400);
PAINT MONO (-1750 3400);
DISPLAY INVISIBLE (-1750 3400);
FORCEPROP 1 LAST BODY_TYPE PLUMBING
J 2
(-1750 3350);
DISPLAY 1.234043 (-1750 3350);
PAINT GREEN (-1750 3350);
DISPLAY INVISIBLE (-1750 3350);
FORCEPROP 1 LAST HDL_TAP TRUE
J 2
(-2075 3275);
DISPLAY 1.234043 (-2075 3275);
PAINT GREEN (-2075 3275);
DISPLAY INVISIBLE (-2075 3275);
FORCEPROP 1 LAST PATH I81
J 2
(-1750 3400);
DISPLAY 0.936170 (-1750 3400);
PAINT GREEN (-1750 3400);
DISPLAY INVISIBLE (-1750 3400);
FORCEADD TAP..6
R 2
(-1750 3000);
FORCEPROP 3 LASTPIN (-1800 3000) SIG_NAME M_L_DQ<24>
J 0
(-1790 3010);
DISPLAY 0.659574 (-1790 3010);
PAINT MONO (-1790 3010);
DISPLAY INVISIBLE (-1790 3010);
FORCEPROP 1 LASTPIN (-1800 3000) BN 24
J 2
(-1750 3010);
DISPLAY 0.617021 (-1750 3010);
PAINT PINK (-1750 3010);
FORCEPROP 2 LAST CDS_LIB mstr_standard
J 2
(-1750 3000);
DISPLAY 0.787234 (-1750 3000);
PAINT MONO (-1750 3000);
DISPLAY INVISIBLE (-1750 3000);
FORCEPROP 1 LAST BODY_TYPE PLUMBING
J 2
(-1750 2950);
DISPLAY 1.234043 (-1750 2950);
PAINT GREEN (-1750 2950);
DISPLAY INVISIBLE (-1750 2950);
FORCEPROP 1 LAST HDL_TAP TRUE
J 2
(-2075 2875);
DISPLAY 1.234043 (-2075 2875);
PAINT GREEN (-2075 2875);
DISPLAY INVISIBLE (-2075 2875);
FORCEPROP 1 LAST PATH I82
J 2
(-1750 3000);
DISPLAY 0.936170 (-1750 3000);
PAINT GREEN (-1750 3000);
DISPLAY INVISIBLE (-1750 3000);
FORCEADD TAP..6
R 2
(-1750 2950);
FORCEPROP 3 LASTPIN (-1800 2950) SIG_NAME M_L_DQ<25>
J 0
(-1790 2960);
DISPLAY 0.659574 (-1790 2960);
PAINT MONO (-1790 2960);
DISPLAY INVISIBLE (-1790 2960);
FORCEPROP 1 LASTPIN (-1800 2950) BN 25
J 2
(-1750 2960);
DISPLAY 0.617021 (-1750 2960);
PAINT PINK (-1750 2960);
FORCEPROP 2 LAST CDS_LIB mstr_standard
J 2
(-1750 2950);
DISPLAY 0.787234 (-1750 2950);
PAINT MONO (-1750 2950);
DISPLAY INVISIBLE (-1750 2950);
FORCEPROP 1 LAST BODY_TYPE PLUMBING
J 2
(-1750 2900);
DISPLAY 1.234043 (-1750 2900);
PAINT GREEN (-1750 2900);
DISPLAY INVISIBLE (-1750 2900);
FORCEPROP 1 LAST HDL_TAP TRUE
J 2
(-2075 2825);
DISPLAY 1.234043 (-2075 2825);
PAINT GREEN (-2075 2825);
DISPLAY INVISIBLE (-2075 2825);
FORCEPROP 1 LAST PATH I83
J 2
(-1750 2950);
DISPLAY 0.936170 (-1750 2950);
PAINT GREEN (-1750 2950);
DISPLAY INVISIBLE (-1750 2950);
FORCEADD TAP..6
R 2
(-1750 3050);
FORCEPROP 3 LASTPIN (-1800 3050) SIG_NAME M_L_DQ<27>
J 0
(-1790 3060);
DISPLAY 0.659574 (-1790 3060);
PAINT MONO (-1790 3060);
DISPLAY INVISIBLE (-1790 3060);
FORCEPROP 1 LASTPIN (-1800 3050) BN 27
J 2
(-1750 3060);
DISPLAY 0.617021 (-1750 3060);
PAINT PINK (-1750 3060);
FORCEPROP 2 LAST CDS_LIB mstr_standard
J 2
(-1750 3050);
DISPLAY 0.787234 (-1750 3050);
PAINT MONO (-1750 3050);
DISPLAY INVISIBLE (-1750 3050);
FORCEPROP 1 LAST BODY_TYPE PLUMBING
J 2
(-1750 3000);
DISPLAY 1.234043 (-1750 3000);
PAINT GREEN (-1750 3000);
DISPLAY INVISIBLE (-1750 3000);
FORCEPROP 1 LAST HDL_TAP TRUE
J 2
(-2075 2925);
DISPLAY 1.234043 (-2075 2925);
PAINT GREEN (-2075 2925);
DISPLAY INVISIBLE (-2075 2925);
FORCEPROP 1 LAST PATH I84
J 2
(-1750 3050);
DISPLAY 0.936170 (-1750 3050);
PAINT GREEN (-1750 3050);
DISPLAY INVISIBLE (-1750 3050);
FORCEADD TAP..6
R 2
(-1750 3150);
FORCEPROP 3 LASTPIN (-1800 3150) SIG_NAME M_L_DQ<29>
J 0
(-1790 3160);
DISPLAY 0.659574 (-1790 3160);
PAINT MONO (-1790 3160);
DISPLAY INVISIBLE (-1790 3160);
FORCEPROP 1 LASTPIN (-1800 3150) BN 29
J 2
(-1750 3160);
DISPLAY 0.617021 (-1750 3160);
PAINT PINK (-1750 3160);
FORCEPROP 2 LAST CDS_LIB mstr_standard
J 2
(-1750 3150);
DISPLAY 0.787234 (-1750 3150);
PAINT MONO (-1750 3150);
DISPLAY INVISIBLE (-1750 3150);
FORCEPROP 1 LAST BODY_TYPE PLUMBING
J 2
(-1750 3100);
DISPLAY 1.234043 (-1750 3100);
PAINT GREEN (-1750 3100);
DISPLAY INVISIBLE (-1750 3100);
FORCEPROP 1 LAST HDL_TAP TRUE
J 2
(-2075 3025);
DISPLAY 1.234043 (-2075 3025);
PAINT GREEN (-2075 3025);
DISPLAY INVISIBLE (-2075 3025);
FORCEPROP 1 LAST PATH I85
J 2
(-1750 3150);
DISPLAY 0.936170 (-1750 3150);
PAINT GREEN (-1750 3150);
DISPLAY INVISIBLE (-1750 3150);
FORCEADD TAP..6
R 2
(-1750 3100);
FORCEPROP 3 LASTPIN (-1800 3100) SIG_NAME M_L_DQ<26>
J 0
(-1790 3110);
DISPLAY 0.659574 (-1790 3110);
PAINT MONO (-1790 3110);
DISPLAY INVISIBLE (-1790 3110);
FORCEPROP 1 LASTPIN (-1800 3100) BN 26
J 2
(-1750 3110);
DISPLAY 0.617021 (-1750 3110);
PAINT PINK (-1750 3110);
FORCEPROP 2 LAST CDS_LIB mstr_standard
J 2
(-1750 3100);
DISPLAY 0.787234 (-1750 3100);
PAINT MONO (-1750 3100);
DISPLAY INVISIBLE (-1750 3100);
FORCEPROP 1 LAST BODY_TYPE PLUMBING
J 2
(-1750 3050);
DISPLAY 1.234043 (-1750 3050);
PAINT GREEN (-1750 3050);
DISPLAY INVISIBLE (-1750 3050);
FORCEPROP 1 LAST HDL_TAP TRUE
J 2
(-2075 2975);
DISPLAY 1.234043 (-2075 2975);
PAINT GREEN (-2075 2975);
DISPLAY INVISIBLE (-2075 2975);
FORCEPROP 1 LAST PATH I86
J 2
(-1750 3100);
DISPLAY 0.936170 (-1750 3100);
PAINT GREEN (-1750 3100);
DISPLAY INVISIBLE (-1750 3100);
FORCEADD TAP..6
R 2
(-1750 2700);
FORCEPROP 3 LASTPIN (-1800 2700) SIG_NAME M_L_DQ<18>
J 0
(-1790 2710);
DISPLAY 0.659574 (-1790 2710);
PAINT MONO (-1790 2710);
DISPLAY INVISIBLE (-1790 2710);
FORCEPROP 1 LASTPIN (-1800 2700) BN 18
J 2
(-1750 2710);
DISPLAY 0.617021 (-1750 2710);
PAINT PINK (-1750 2710);
FORCEPROP 2 LAST CDS_LIB mstr_standard
J 2
(-1750 2700);
DISPLAY 0.787234 (-1750 2700);
PAINT MONO (-1750 2700);
DISPLAY INVISIBLE (-1750 2700);
FORCEPROP 1 LAST BODY_TYPE PLUMBING
J 2
(-1750 2650);
DISPLAY 1.234043 (-1750 2650);
PAINT GREEN (-1750 2650);
DISPLAY INVISIBLE (-1750 2650);
FORCEPROP 1 LAST HDL_TAP TRUE
J 2
(-2075 2575);
DISPLAY 1.234043 (-2075 2575);
PAINT GREEN (-2075 2575);
DISPLAY INVISIBLE (-2075 2575);
FORCEPROP 1 LAST PATH I87
J 2
(-1750 2700);
DISPLAY 0.936170 (-1750 2700);
PAINT GREEN (-1750 2700);
DISPLAY INVISIBLE (-1750 2700);
FORCEADD TAP..6
R 2
(-1750 2750);
FORCEPROP 3 LASTPIN (-1800 2750) SIG_NAME M_L_DQ<21>
J 0
(-1790 2760);
DISPLAY 0.659574 (-1790 2760);
PAINT MONO (-1790 2760);
DISPLAY INVISIBLE (-1790 2760);
FORCEPROP 1 LASTPIN (-1800 2750) BN 21
J 2
(-1750 2760);
DISPLAY 0.617021 (-1750 2760);
PAINT PINK (-1750 2760);
FORCEPROP 2 LAST CDS_LIB mstr_standard
J 2
(-1750 2750);
DISPLAY 0.787234 (-1750 2750);
PAINT MONO (-1750 2750);
DISPLAY INVISIBLE (-1750 2750);
FORCEPROP 1 LAST BODY_TYPE PLUMBING
J 2
(-1750 2700);
DISPLAY 1.234043 (-1750 2700);
PAINT GREEN (-1750 2700);
DISPLAY INVISIBLE (-1750 2700);
FORCEPROP 1 LAST HDL_TAP TRUE
J 2
(-2075 2625);
DISPLAY 1.234043 (-2075 2625);
PAINT GREEN (-2075 2625);
DISPLAY INVISIBLE (-2075 2625);
FORCEPROP 1 LAST PATH I88
J 2
(-1750 2750);
DISPLAY 0.936170 (-1750 2750);
PAINT GREEN (-1750 2750);
DISPLAY INVISIBLE (-1750 2750);
FORCEADD TAP..6
R 2
(-1750 2800);
FORCEPROP 3 LASTPIN (-1800 2800) SIG_NAME M_L_DQ<20>
J 0
(-1790 2810);
DISPLAY 0.659574 (-1790 2810);
PAINT MONO (-1790 2810);
DISPLAY INVISIBLE (-1790 2810);
FORCEPROP 1 LASTPIN (-1800 2800) BN 20
J 2
(-1750 2810);
DISPLAY 0.617021 (-1750 2810);
PAINT PINK (-1750 2810);
FORCEPROP 2 LAST CDS_LIB mstr_standard
J 2
(-1750 2800);
DISPLAY 0.787234 (-1750 2800);
PAINT MONO (-1750 2800);
DISPLAY INVISIBLE (-1750 2800);
FORCEPROP 1 LAST BODY_TYPE PLUMBING
J 2
(-1750 2750);
DISPLAY 1.234043 (-1750 2750);
PAINT GREEN (-1750 2750);
DISPLAY INVISIBLE (-1750 2750);
FORCEPROP 1 LAST HDL_TAP TRUE
J 2
(-2075 2675);
DISPLAY 1.234043 (-2075 2675);
PAINT GREEN (-2075 2675);
DISPLAY INVISIBLE (-2075 2675);
FORCEPROP 1 LAST PATH I89
J 2
(-1750 2800);
DISPLAY 0.936170 (-1750 2800);
PAINT GREEN (-1750 2800);
DISPLAY INVISIBLE (-1750 2800);
FORCEADD TAP..6
R 2
(900 4600);
FORCEPROP 3 LASTPIN (850 4600) SIG_NAME M_L_DQS_DN<12>
J 0
(860 4610);
DISPLAY 0.659574 (860 4610);
PAINT MONO (860 4610);
DISPLAY INVISIBLE (860 4610);
FORCEPROP 1 LASTPIN (850 4600) BN 12
J 2
(900 4610);
DISPLAY 0.617021 (900 4610);
PAINT PINK (900 4610);
FORCEPROP 2 LAST CDS_LIB mstr_standard
J 0
(900 4600);
DISPLAY 0.787234 (900 4600);
PAINT MONO (900 4600);
DISPLAY INVISIBLE (900 4600);
FORCEPROP 1 LAST BODY_TYPE PLUMBING
J 2
(900 4550);
DISPLAY 1.234043 (900 4550);
PAINT GREEN (900 4550);
DISPLAY INVISIBLE (900 4550);
FORCEPROP 1 LAST HDL_TAP TRUE
J 2
(575 4475);
DISPLAY 1.234043 (575 4475);
PAINT GREEN (575 4475);
DISPLAY INVISIBLE (575 4475);
FORCEPROP 1 LAST PATH I9
J 2
(900 4600);
DISPLAY 0.936170 (900 4600);
PAINT GREEN (900 4600);
DISPLAY INVISIBLE (900 4600);
FORCEADD TAP..6
R 2
(-1750 2900);
FORCEPROP 3 LASTPIN (-1800 2900) SIG_NAME M_L_DQ<22>
J 0
(-1790 2910);
DISPLAY 0.659574 (-1790 2910);
PAINT MONO (-1790 2910);
DISPLAY INVISIBLE (-1790 2910);
FORCEPROP 1 LASTPIN (-1800 2900) BN 22
J 2
(-1750 2910);
DISPLAY 0.617021 (-1750 2910);
PAINT PINK (-1750 2910);
FORCEPROP 2 LAST CDS_LIB mstr_standard
J 2
(-1750 2900);
DISPLAY 0.787234 (-1750 2900);
PAINT MONO (-1750 2900);
DISPLAY INVISIBLE (-1750 2900);
FORCEPROP 1 LAST BODY_TYPE PLUMBING
J 2
(-1750 2850);
DISPLAY 1.234043 (-1750 2850);
PAINT GREEN (-1750 2850);
DISPLAY INVISIBLE (-1750 2850);
FORCEPROP 1 LAST HDL_TAP TRUE
J 2
(-2075 2775);
DISPLAY 1.234043 (-2075 2775);
PAINT GREEN (-2075 2775);
DISPLAY INVISIBLE (-2075 2775);
FORCEPROP 1 LAST PATH I90
J 2
(-1750 2900);
DISPLAY 0.936170 (-1750 2900);
PAINT GREEN (-1750 2900);
DISPLAY INVISIBLE (-1750 2900);
FORCEADD TAP..6
R 2
(-1750 2850);
FORCEPROP 3 LASTPIN (-1800 2850) SIG_NAME M_L_DQ<23>
J 0
(-1790 2860);
DISPLAY 0.659574 (-1790 2860);
PAINT MONO (-1790 2860);
DISPLAY INVISIBLE (-1790 2860);
FORCEPROP 1 LASTPIN (-1800 2850) BN 23
J 2
(-1750 2860);
DISPLAY 0.617021 (-1750 2860);
PAINT PINK (-1750 2860);
FORCEPROP 2 LAST CDS_LIB mstr_standard
J 2
(-1750 2850);
DISPLAY 0.787234 (-1750 2850);
PAINT MONO (-1750 2850);
DISPLAY INVISIBLE (-1750 2850);
FORCEPROP 1 LAST BODY_TYPE PLUMBING
J 2
(-1750 2800);
DISPLAY 1.234043 (-1750 2800);
PAINT GREEN (-1750 2800);
DISPLAY INVISIBLE (-1750 2800);
FORCEPROP 1 LAST HDL_TAP TRUE
J 2
(-2075 2725);
DISPLAY 1.234043 (-2075 2725);
PAINT GREEN (-2075 2725);
DISPLAY INVISIBLE (-2075 2725);
FORCEPROP 1 LAST PATH I91
J 2
(-1750 2850);
DISPLAY 0.936170 (-1750 2850);
PAINT GREEN (-1750 2850);
DISPLAY INVISIBLE (-1750 2850);
FORCEADD TAP..6
R 2
(-1750 2450);
FORCEPROP 3 LASTPIN (-1800 2450) SIG_NAME M_L_DQ<15>
J 0
(-1790 2460);
DISPLAY 0.659574 (-1790 2460);
PAINT MONO (-1790 2460);
DISPLAY INVISIBLE (-1790 2460);
FORCEPROP 1 LASTPIN (-1800 2450) BN 15
J 2
(-1750 2460);
DISPLAY 0.617021 (-1750 2460);
PAINT PINK (-1750 2460);
FORCEPROP 2 LAST CDS_LIB mstr_standard
J 2
(-1750 2450);
DISPLAY 0.787234 (-1750 2450);
PAINT MONO (-1750 2450);
DISPLAY INVISIBLE (-1750 2450);
FORCEPROP 1 LAST BODY_TYPE PLUMBING
J 2
(-1750 2400);
DISPLAY 1.234043 (-1750 2400);
PAINT GREEN (-1750 2400);
DISPLAY INVISIBLE (-1750 2400);
FORCEPROP 1 LAST HDL_TAP TRUE
J 2
(-2075 2325);
DISPLAY 1.234043 (-2075 2325);
PAINT GREEN (-2075 2325);
DISPLAY INVISIBLE (-2075 2325);
FORCEPROP 1 LAST PATH I92
J 2
(-1750 2450);
DISPLAY 0.936170 (-1750 2450);
PAINT GREEN (-1750 2450);
DISPLAY INVISIBLE (-1750 2450);
FORCEADD TAP..6
R 2
(-1750 2500);
FORCEPROP 3 LASTPIN (-1800 2500) SIG_NAME M_L_DQ<14>
J 0
(-1790 2510);
DISPLAY 0.659574 (-1790 2510);
PAINT MONO (-1790 2510);
DISPLAY INVISIBLE (-1790 2510);
FORCEPROP 1 LASTPIN (-1800 2500) BN 14
J 2
(-1750 2510);
DISPLAY 0.617021 (-1750 2510);
PAINT PINK (-1750 2510);
FORCEPROP 2 LAST CDS_LIB mstr_standard
J 2
(-1750 2500);
DISPLAY 0.787234 (-1750 2500);
PAINT MONO (-1750 2500);
DISPLAY INVISIBLE (-1750 2500);
FORCEPROP 1 LAST BODY_TYPE PLUMBING
J 2
(-1750 2450);
DISPLAY 1.234043 (-1750 2450);
PAINT GREEN (-1750 2450);
DISPLAY INVISIBLE (-1750 2450);
FORCEPROP 1 LAST HDL_TAP TRUE
J 2
(-2075 2375);
DISPLAY 1.234043 (-2075 2375);
PAINT GREEN (-2075 2375);
DISPLAY INVISIBLE (-2075 2375);
FORCEPROP 1 LAST PATH I93
J 2
(-1750 2500);
DISPLAY 0.936170 (-1750 2500);
PAINT GREEN (-1750 2500);
DISPLAY INVISIBLE (-1750 2500);
FORCEADD TAP..6
R 2
(-1750 2600);
FORCEPROP 3 LASTPIN (-1800 2600) SIG_NAME M_L_DQ<16>
J 0
(-1790 2610);
DISPLAY 0.659574 (-1790 2610);
PAINT MONO (-1790 2610);
DISPLAY INVISIBLE (-1790 2610);
FORCEPROP 1 LASTPIN (-1800 2600) BN 16
J 2
(-1750 2610);
DISPLAY 0.617021 (-1750 2610);
PAINT PINK (-1750 2610);
FORCEPROP 2 LAST CDS_LIB mstr_standard
J 2
(-1750 2600);
DISPLAY 0.787234 (-1750 2600);
PAINT MONO (-1750 2600);
DISPLAY INVISIBLE (-1750 2600);
FORCEPROP 1 LAST BODY_TYPE PLUMBING
J 2
(-1750 2550);
DISPLAY 1.234043 (-1750 2550);
PAINT GREEN (-1750 2550);
DISPLAY INVISIBLE (-1750 2550);
FORCEPROP 1 LAST HDL_TAP TRUE
J 2
(-2075 2475);
DISPLAY 1.234043 (-2075 2475);
PAINT GREEN (-2075 2475);
DISPLAY INVISIBLE (-2075 2475);
FORCEPROP 1 LAST PATH I94
J 2
(-1750 2600);
DISPLAY 0.936170 (-1750 2600);
PAINT GREEN (-1750 2600);
DISPLAY INVISIBLE (-1750 2600);
FORCEADD TAP..6
R 2
(-1750 2550);
FORCEPROP 3 LASTPIN (-1800 2550) SIG_NAME M_L_DQ<17>
J 0
(-1790 2560);
DISPLAY 0.659574 (-1790 2560);
PAINT MONO (-1790 2560);
DISPLAY INVISIBLE (-1790 2560);
FORCEPROP 1 LASTPIN (-1800 2550) BN 17
J 2
(-1750 2560);
DISPLAY 0.617021 (-1750 2560);
PAINT PINK (-1750 2560);
FORCEPROP 2 LAST CDS_LIB mstr_standard
J 2
(-1750 2550);
DISPLAY 0.787234 (-1750 2550);
PAINT MONO (-1750 2550);
DISPLAY INVISIBLE (-1750 2550);
FORCEPROP 1 LAST BODY_TYPE PLUMBING
J 2
(-1750 2500);
DISPLAY 1.234043 (-1750 2500);
PAINT GREEN (-1750 2500);
DISPLAY INVISIBLE (-1750 2500);
FORCEPROP 1 LAST HDL_TAP TRUE
J 2
(-2075 2425);
DISPLAY 1.234043 (-2075 2425);
PAINT GREEN (-2075 2425);
DISPLAY INVISIBLE (-2075 2425);
FORCEPROP 1 LAST PATH I95
J 2
(-1750 2550);
DISPLAY 0.936170 (-1750 2550);
PAINT GREEN (-1750 2550);
DISPLAY INVISIBLE (-1750 2550);
FORCEADD TAP..6
R 2
(-1750 2650);
FORCEPROP 3 LASTPIN (-1800 2650) SIG_NAME M_L_DQ<19>
J 0
(-1790 2660);
DISPLAY 0.659574 (-1790 2660);
PAINT MONO (-1790 2660);
DISPLAY INVISIBLE (-1790 2660);
FORCEPROP 1 LASTPIN (-1800 2650) BN 19
J 2
(-1750 2660);
DISPLAY 0.617021 (-1750 2660);
PAINT PINK (-1750 2660);
FORCEPROP 2 LAST CDS_LIB mstr_standard
J 2
(-1750 2650);
DISPLAY 0.787234 (-1750 2650);
PAINT MONO (-1750 2650);
DISPLAY INVISIBLE (-1750 2650);
FORCEPROP 1 LAST BODY_TYPE PLUMBING
J 2
(-1750 2600);
DISPLAY 1.234043 (-1750 2600);
PAINT GREEN (-1750 2600);
DISPLAY INVISIBLE (-1750 2600);
FORCEPROP 1 LAST HDL_TAP TRUE
J 2
(-2075 2525);
DISPLAY 1.234043 (-2075 2525);
PAINT GREEN (-2075 2525);
DISPLAY INVISIBLE (-2075 2525);
FORCEPROP 1 LAST PATH I96
J 2
(-1750 2650);
DISPLAY 0.936170 (-1750 2650);
PAINT GREEN (-1750 2650);
DISPLAY INVISIBLE (-1750 2650);
FORCEADD TAP..6
R 2
(-1750 2400);
FORCEPROP 3 LASTPIN (-1800 2400) SIG_NAME M_L_DQ<12>
J 0
(-1790 2410);
DISPLAY 0.659574 (-1790 2410);
PAINT MONO (-1790 2410);
DISPLAY INVISIBLE (-1790 2410);
FORCEPROP 1 LASTPIN (-1800 2400) BN 12
J 2
(-1750 2410);
DISPLAY 0.617021 (-1750 2410);
PAINT PINK (-1750 2410);
FORCEPROP 2 LAST CDS_LIB mstr_standard
J 2
(-1750 2400);
DISPLAY 0.787234 (-1750 2400);
PAINT MONO (-1750 2400);
DISPLAY INVISIBLE (-1750 2400);
FORCEPROP 1 LAST BODY_TYPE PLUMBING
J 2
(-1750 2350);
DISPLAY 1.234043 (-1750 2350);
PAINT GREEN (-1750 2350);
DISPLAY INVISIBLE (-1750 2350);
FORCEPROP 1 LAST HDL_TAP TRUE
J 2
(-2075 2275);
DISPLAY 1.234043 (-2075 2275);
PAINT GREEN (-2075 2275);
DISPLAY INVISIBLE (-2075 2275);
FORCEPROP 1 LAST PATH I97
J 2
(-1750 2400);
DISPLAY 0.936170 (-1750 2400);
PAINT GREEN (-1750 2400);
DISPLAY INVISIBLE (-1750 2400);
FORCEADD TAP..6
R 2
(-1750 2300);
FORCEPROP 3 LASTPIN (-1800 2300) SIG_NAME M_L_DQ<10>
J 0
(-1790 2310);
DISPLAY 0.659574 (-1790 2310);
PAINT MONO (-1790 2310);
DISPLAY INVISIBLE (-1790 2310);
FORCEPROP 1 LASTPIN (-1800 2300) BN 10
J 2
(-1750 2310);
DISPLAY 0.617021 (-1750 2310);
PAINT PINK (-1750 2310);
FORCEPROP 2 LAST CDS_LIB mstr_standard
J 2
(-1750 2300);
DISPLAY 0.787234 (-1750 2300);
PAINT MONO (-1750 2300);
DISPLAY INVISIBLE (-1750 2300);
FORCEPROP 1 LAST BODY_TYPE PLUMBING
J 2
(-1750 2250);
DISPLAY 1.234043 (-1750 2250);
PAINT GREEN (-1750 2250);
DISPLAY INVISIBLE (-1750 2250);
FORCEPROP 1 LAST HDL_TAP TRUE
J 2
(-2075 2175);
DISPLAY 1.234043 (-2075 2175);
PAINT GREEN (-2075 2175);
DISPLAY INVISIBLE (-2075 2175);
FORCEPROP 1 LAST PATH I98
J 2
(-1750 2300);
DISPLAY 0.936170 (-1750 2300);
PAINT GREEN (-1750 2300);
DISPLAY INVISIBLE (-1750 2300);
FORCEADD TAP..6
R 2
(-1750 2350);
FORCEPROP 3 LASTPIN (-1800 2350) SIG_NAME M_L_DQ<13>
J 0
(-1790 2360);
DISPLAY 0.659574 (-1790 2360);
PAINT MONO (-1790 2360);
DISPLAY INVISIBLE (-1790 2360);
FORCEPROP 1 LASTPIN (-1800 2350) BN 13
J 2
(-1750 2360);
DISPLAY 0.617021 (-1750 2360);
PAINT PINK (-1750 2360);
FORCEPROP 2 LAST CDS_LIB mstr_standard
J 2
(-1750 2350);
DISPLAY 0.787234 (-1750 2350);
PAINT MONO (-1750 2350);
DISPLAY INVISIBLE (-1750 2350);
FORCEPROP 1 LAST BODY_TYPE PLUMBING
J 2
(-1750 2300);
DISPLAY 1.234043 (-1750 2300);
PAINT GREEN (-1750 2300);
DISPLAY INVISIBLE (-1750 2300);
FORCEPROP 1 LAST HDL_TAP TRUE
J 2
(-2075 2225);
DISPLAY 1.234043 (-2075 2225);
PAINT GREEN (-2075 2225);
DISPLAY INVISIBLE (-2075 2225);
FORCEPROP 1 LAST PATH I99
J 2
(-1750 2350);
DISPLAY 0.936170 (-1750 2350);
PAINT GREEN (-1750 2350);
DISPLAY INVISIBLE (-1750 2350);
FORCEADD BOM_NOTE..1
(-5000 5275);
FORCEPROP 0 LAST L1 STUFF FOR SKU A & B
J 0
(-5150 5175);
DISPLAY 1.063830 (-5150 5175);
PAINT WHITE (-5150 5175);
FORCEPROP 2 LAST CDS_LIB mstr_symbols
J 0
(-5000 5275);
PAINT ORANGE (-5000 5275);
DISPLAY INVISIBLE (-5000 5275);
FORCEPROP 2 LAST BOM_COST SB
J 0
(-5150 5250);
DISPLAY 1.361702 (-5150 5250);
PAINT ORANGE (-5150 5250);
DISPLAY INVISIBLE (-5150 5250);
FORCEPROP 1 LAST COMMENT_BODY TRUE
J 0
(-4975 5375);
DISPLAY 1.319149 (-4975 5375);
PAINT ORANGE (-4975 5375);
DISPLAY INVISIBLE (-4975 5375);
FORCEPROP 2 LAST ROOM SB_HEADERS
J 0
(-5150 5250);
DISPLAY 1.361702 (-5150 5250);
PAINT ORANGE (-5150 5250);
DISPLAY INVISIBLE (-5150 5250);
FORCEADD INTEL_CORP_BPAGE..1
(2650 500);
FORCEPROP 1 LAST CDS_CON_LAST_MODIFIED Tue Dec 01 11:51:45 2015
J 0
(1225 825);
DISPLAY 0.787234 (1225 825);
PAINT ORANGE (1225 825);
DISPLAY INVISIBLE (1225 825);
FORCEPROP 1 LAST CUSTOM_TXT_CDS <CURRENT_DESIGN_SHEET> OF <TOTAL_DESIGN_SHEETS>
J 0
(2150 525);
PAINT GREEN (2150 525);
FORCEPROP 2 LAST CUSTOM_TXT_CDS <XR_PAGE_TITLE>
J 0
(-5240 5750);
DISPLAY 0.638298 (-5240 5750);
PAINT PINK (-5240 5750);
DISPLAY INVISIBLE (-5240 5750);
FORCEPROP 2 LAST CUSTOM_TXT_CDS <CON_LAST_MODIFIED>
J 0
(725 850);
DISPLAY 1.617021 (725 850);
PAINT GREEN (725 850);
FORCEPROP 1 LAST SCH_ADDRESS3 Santa Clara, CA 95052-8119
J 0
(-1325 525);
DISPLAY 0.617021 (-1325 525);
PAINT GREEN (-1325 525);
FORCEPROP 1 LAST SCH_ADDRESS2 P.O. BOX 58119
J 0
(-1325 575);
DISPLAY 0.617021 (-1325 575);
PAINT GREEN (-1325 575);
FORCEPROP 1 LAST SCH_ADDRESS1 2200 Mission College Blvd.
J 0
(-1325 625);
DISPLAY 0.617021 (-1325 625);
PAINT GREEN (-1325 625);
FORCEPROP 1 LAST SCH_TITLE CPU1 DDR4 CH L DIMM0
J 0
(-5300 550);
DISPLAY 1.212766 (-5300 550);
PAINT WHITE (-5300 550);
FORCEPROP 1 LAST SCH_NUMBER H4694802
J 0
(1350 650);
DISPLAY 1.212766 (1350 650);
PAINT YELLOW (1350 650);
FORCEPROP 1 LAST SCH_DEPT BESD
J 1
(-1800 600);
DISPLAY 1.212766 (-1800 600);
PAINT YELLOW (-1800 600);
FORCEPROP 1 LAST SCH_REV 2.420
J 0
(2400 650);
DISPLAY 0.978723 (2400 650);
PAINT YELLOW (2400 650);
FORCEPROP 2 LAST PAGE_BORDER TRUE
J 0
(-5240 5750);
DISPLAY 0.680851 (-5240 5750);
PAINT PINK (-5240 5750);
DISPLAY INVISIBLE (-5240 5750);
FORCEPROP 2 LAST CDS_LIB mstr_symbols
J 0
(2650 500);
DISPLAY 0.787234 (2650 500);
PAINT MONO (2650 500);
DISPLAY INVISIBLE (2650 500);
FORCEPROP 1 LAST COMMENT_BODY TRUE
J 0
(2660 510);
DISPLAY 0.382979 (2660 510);
PAINT GREEN (2660 510);
DISPLAY INVISIBLE (2660 510);
FORCEPROP 2 LAST CDS_XR_PAGE_TITLE CR-85 : @BASEBOARD_FAB2_LIB.BASEBOARD_FAB2(SCH_1):PAGE85
J 0
(-5240 5750);
DISPLAY 0.638298 (-5240 5750);
PAINT PINK (-5240 5750);
DISPLAY INVISIBLE (-5240 5750);
WIRE 17 -1 (750 5175)(750 5200);
WIRE 17 -1 (750 5075)(750 5175);
WIRE 17 -1 (1550 5200)(750 5200);
FORCEPROP 2 LAST SIG_NAME M_L_DQS_DP<17:0>
J 0
(1000 5210);
DISPLAY 0.617021 (1000 5210);
PAINT ORANGE (1000 5210);
WIRE 17 -1 (750 4375)(750 4475);
WIRE 17 -1 (750 4275)(750 4375);
WIRE 17 -1 (750 4475)(750 4575);
WIRE 17 -1 (750 4575)(750 4675);
WIRE 17 -1 (750 4175)(750 4275);
WIRE 17 -1 (750 4075)(750 4175);
WIRE 17 -1 (750 4675)(750 4775);
WIRE 17 -1 (750 4775)(750 4875);
WIRE 17 -1 (750 3975)(750 4075);
WIRE 17 -1 (750 3875)(750 3975);
WIRE 17 -1 (750 4875)(750 4975);
WIRE 17 -1 (750 4975)(750 5075);
WIRE 17 -1 (750 3775)(750 3875);
WIRE 17 -1 (750 3675)(750 3775);
WIRE 17 -1 (750 3575)(750 3675);
WIRE 17 -1 (750 3475)(750 3575);
WIRE 17 -1 (950 4325)(950 4425);
WIRE 17 -1 (950 4225)(950 4325);
WIRE 17 -1 (950 4425)(950 4525);
WIRE 17 -1 (950 4525)(950 4625);
WIRE 17 -1 (950 4125)(950 4225);
WIRE 17 -1 (950 4025)(950 4125);
WIRE 17 -1 (950 4625)(950 4725);
WIRE 17 -1 (950 4725)(950 4825);
WIRE 17 -1 (950 3925)(950 4025);
WIRE 17 -1 (950 3825)(950 3925);
WIRE 17 -1 (950 4825)(950 4925);
WIRE 17 -1 (950 4925)(950 5025);
WIRE 17 -1 (950 3725)(950 3825);
WIRE 17 -1 (950 3625)(950 3725);
WIRE 17 -1 (950 5025)(950 5125);
WIRE 17 -1 (950 5125)(950 5150);
WIRE 17 -1 (950 3525)(950 3625);
WIRE 17 -1 (950 3425)(950 3525);
WIRE 17 -1 (1550 5150)(950 5150);
FORCEPROP 2 LAST SIG_NAME M_L_DQS_DN<17:0>
J 0
(1000 5160);
DISPLAY 0.617021 (1000 5160);
PAINT ORANGE (1000 5160);
WIRE 17 -1 (-1700 4950)(-1700 4925);
WIRE 17 -1 (-1225 4950)(-1700 4950);
FORCEPROP 2 LAST SIG_NAME M_L_DQ<63:0>
J 0
(-1660 4960);
DISPLAY 0.617021 (-1660 4960);
PAINT ORANGE (-1660 4960);
WIRE 17 -1 (-1700 4875)(-1700 4925);
WIRE 17 -1 (-1700 4825)(-1700 4875);
WIRE 17 -1 (-1700 4725)(-1700 4775);
WIRE 17 -1 (-1700 4675)(-1700 4725);
WIRE 17 -1 (-1700 4775)(-1700 4825);
WIRE 17 -1 (-1700 4625)(-1700 4675);
WIRE 17 -1 (-1700 4575)(-1700 4625);
WIRE 17 -1 (-1700 4525)(-1700 4575);
WIRE 17 -1 (-1700 4475)(-1700 4525);
WIRE 17 -1 (-1700 4425)(-1700 4475);
WIRE 17 -1 (-1700 4375)(-1700 4425);
WIRE 17 -1 (-1700 4325)(-1700 4375);
WIRE 17 -1 (-1700 4275)(-1700 4325);
WIRE 17 -1 (-1700 4225)(-1700 4275);
WIRE 17 -1 (-1700 4175)(-1700 4225);
WIRE 17 -1 (-1700 4125)(-1700 4175);
WIRE 17 -1 (-1700 4075)(-1700 4125);
WIRE 17 -1 (-1700 4025)(-1700 4075);
WIRE 17 -1 (-1700 3975)(-1700 4025);
WIRE 17 -1 (-1700 3925)(-1700 3975);
WIRE 17 -1 (-1700 3875)(-1700 3925);
WIRE 17 -1 (-1700 3825)(-1700 3875);
WIRE 17 -1 (-1700 3775)(-1700 3825);
WIRE 17 -1 (-1700 3725)(-1700 3775);
WIRE 17 -1 (-1700 3675)(-1700 3725);
WIRE 17 -1 (-1700 3625)(-1700 3675);
WIRE 17 -1 (-1700 3575)(-1700 3625);
WIRE 17 -1 (-1700 3525)(-1700 3575);
WIRE 17 -1 (-1700 3475)(-1700 3525);
WIRE 17 -1 (-1700 3425)(-1700 3475);
WIRE 17 -1 (-1700 3375)(-1700 3425);
WIRE 17 -1 (-1700 3325)(-1700 3375);
WIRE 17 -1 (-1700 3275)(-1700 3325);
WIRE 17 -1 (-3300 4875)(-3300 4925);
WIRE 17 -1 (-3300 4825)(-3300 4875);
WIRE 17 -1 (-3300 4925)(-3300 4950);
WIRE 17 -1 (-3800 4950)(-3300 4950);
FORCEPROP 2 LAST SIG_NAME M_L_MA<17:0>
J 0
(-3775 4960);
DISPLAY 0.617021 (-3775 4960);
PAINT ORANGE (-3775 4960);
WIRE 17 -1 (-3300 4775)(-3300 4825);
WIRE 17 -1 (-3300 4725)(-3300 4775);
WIRE 17 -1 (-3300 4675)(-3300 4725);
WIRE 17 -1 (-3300 4625)(-3300 4675);
WIRE 17 -1 (-3300 4575)(-3300 4625);
WIRE 17 -1 (-3300 4525)(-3300 4575);
WIRE 17 -1 (-3300 4475)(-3300 4525);
WIRE 17 -1 (-3300 4425)(-3300 4475);
WIRE 17 -1 (-3300 4375)(-3300 4425);
WIRE 17 -1 (-3300 4325)(-3300 4375);
WIRE 17 -1 (-3300 4275)(-3300 4325);
WIRE 17 -1 (-3300 4225)(-3300 4275);
WIRE 17 -1 (-3300 4175)(-3300 4225);
WIRE 17 -1 (-3300 4125)(-3300 4175);
WIRE 17 -1 (-3300 4075)(-3300 4125);
WIRE 17 -1 (-1700 3225)(-1700 3275);
WIRE 17 -1 (-1700 3175)(-1700 3225);
WIRE 17 -1 (-1700 3125)(-1700 3175);
WIRE 17 -1 (-1700 3075)(-1700 3125);
WIRE 17 -1 (-1700 3025)(-1700 3075);
WIRE 17 -1 (-1700 2975)(-1700 3025);
WIRE 17 -1 (-1700 2925)(-1700 2975);
WIRE 17 -1 (-1700 2875)(-1700 2925);
WIRE 17 -1 (-1700 2825)(-1700 2875);
WIRE 17 -1 (-1700 2775)(-1700 2825);
WIRE 17 -1 (-1700 2725)(-1700 2775);
WIRE 17 -1 (-1700 2675)(-1700 2725);
WIRE 17 -1 (-1700 2625)(-1700 2675);
WIRE 17 -1 (-1700 2575)(-1700 2625);
WIRE 17 -1 (-1700 2525)(-1700 2575);
WIRE 17 -1 (-1700 2475)(-1700 2525);
WIRE 17 -1 (-1700 2425)(-1700 2475);
WIRE 17 -1 (-1700 2375)(-1700 2425);
WIRE 17 -1 (-1700 2325)(-1700 2375);
WIRE 17 -1 (-1700 2275)(-1700 2325);
WIRE 17 -1 (-1700 2225)(-1700 2275);
WIRE 17 -1 (-1700 2175)(-1700 2225);
WIRE 17 -1 (-1700 2125)(-1700 2175);
WIRE 17 -1 (-1700 2075)(-1700 2125);
WIRE 17 -1 (-1700 2025)(-1700 2075);
WIRE 17 -1 (-1700 1975)(-1700 2025);
WIRE 17 -1 (-1700 1925)(-1700 1975);
WIRE 17 -1 (-1700 1875)(-1700 1925);
WIRE 17 -1 (-1700 1825)(-1700 1875);
WIRE 17 -1 (-1700 1775)(-1700 1825);
WIRE 17 -1 (-3300 3275)(-3300 3325);
WIRE 17 -1 (-3300 3325)(-3300 3375);
WIRE 17 -1 (-3300 3375)(-3300 3425);
WIRE 17 -1 (-3300 3425)(-3300 3450);
WIRE 17 -1 (-3300 3450)(-3800 3450);
FORCEPROP 2 LAST SIG_NAME M_L_CS_N<7:0>
J 0
(-3775 3460);
DISPLAY 0.617021 (-3775 3460);
PAINT ORANGE (-3775 3460);
WIRE 17 -1 (-3300 3125)(-3300 3175);
WIRE 17 -1 (-3300 3175)(-3300 3200);
WIRE 17 -1 (-3300 3200)(-3800 3200);
FORCEPROP 2 LAST SIG_NAME M_L_CKE<3:0>
J 0
(-3775 3210);
DISPLAY 0.617021 (-3775 3210);
PAINT ORANGE (-3775 3210);
WIRE 17 -1 (-3300 3025)(-3300 3050);
WIRE 17 -1 (-3300 2975)(-3300 3025);
WIRE 17 -1 (-3300 3050)(-3800 3050);
FORCEPROP 2 LAST SIG_NAME M_L_ODT<3:0>
J 0
(-3775 3060);
DISPLAY 0.617021 (-3775 3060);
PAINT ORANGE (-3775 3060);
WIRE 17 -1 (-3300 2875)(-3300 2900);
WIRE 17 -1 (-3300 2825)(-3300 2875);
WIRE 17 -1 (-3300 2900)(-3800 2900);
FORCEPROP 2 LAST SIG_NAME M_L_ECC<7:0>
J 0
(-3775 2910);
DISPLAY 0.617021 (-3775 2910);
PAINT ORANGE (-3775 2910);
WIRE 17 -1 (-3500 3675)(-3500 3575);
WIRE 17 -1 (-3500 3700)(-3500 3675);
WIRE 17 -1 (-3500 3700)(-3800 3700);
FORCEPROP 2 LAST SIG_NAME M_L_CLK_DN<3:0>
J 0
(-3800 3710);
DISPLAY 0.617021 (-3800 3710);
PAINT ORANGE (-3800 3710);
WIRE 17 -1 (-3300 2525)(-3300 2575);
WIRE 17 -1 (-3300 2575)(-3300 2625);
WIRE 17 -1 (-3300 2625)(-3300 2675);
WIRE 17 -1 (-3300 2675)(-3300 2725);
WIRE 17 -1 (-3300 2725)(-3300 2775);
WIRE 17 -1 (-3300 2775)(-3300 2825);
WIRE 17 -1 (-3300 3625)(-3300 3725);
WIRE 17 -1 (-3300 3725)(-3300 3750);
WIRE 17 -1 (-3300 3750)(-3800 3750);
FORCEPROP 2 LAST SIG_NAME M_L_CLK_DP<3:0>
J 0
(-3800 3760);
DISPLAY 0.617021 (-3800 3760);
PAINT ORANGE (-3800 3760);
WIRE 17 -1 (-3300 4000)(-3300 3975);
WIRE 17 -1 (-3300 4000)(-3800 4000);
FORCEPROP 2 LAST SIG_NAME M_L_BA<1:0>
J 0
(-3775 4010);
DISPLAY 0.617021 (-3775 4010);
PAINT ORANGE (-3775 4010);
WIRE 17 -1 (-3300 3925)(-3300 3975);
WIRE 17 -1 (-3300 3825)(-3300 3875);
WIRE 17 -1 (-3300 3875)(-3800 3875);
FORCEPROP 2 LAST SIG_NAME M_L_BG<1:0>
J 0
(-3775 3885);
DISPLAY 0.617021 (-3775 3885);
PAINT ORANGE (-3775 3885);
WIRE 16 -1 (-950 1200)(-750 1200);
WIRE 16 -1 (-950 1200)(-950 1250);
WIRE 16 -1 (-950 1250)(-750 1250);
WIRE 16 -1 (-950 1250)(-950 1300);
WIRE 16 -1 (-950 1300)(-750 1300);
WIRE 16 -1 (-950 1300)(-950 1350);
WIRE 16 -1 (-950 1350)(-750 1350);
WIRE 16 -1 (-950 1350)(-950 1400);
WIRE 16 -1 (-950 1400)(-750 1400);
WIRE 16 -1 (-950 1400)(-950 1450);
WIRE 16 -1 (-950 1450)(-750 1450);
WIRE 16 -1 (-950 1450)(-950 1500);
WIRE 16 -1 (-950 1500)(-950 1550);
WIRE 16 -1 (-950 1500)(-750 1500);
WIRE 16 -1 (-950 1550)(-750 1550);
WIRE 16 -1 (-950 1550)(-950 1600);
WIRE 16 -1 (-950 1600)(-750 1600);
WIRE 16 -1 (-950 1600)(-950 1650);
WIRE 16 -1 (-950 1650)(-750 1650);
WIRE 16 -1 (-950 1650)(-950 1700);
WIRE 16 -1 (-950 1700)(-750 1700);
WIRE 16 -1 (-950 1700)(-950 1750);
WIRE 16 -1 (-950 1750)(-750 1750);
WIRE 16 -1 (-950 1750)(-950 1800);
WIRE 16 -1 (-950 1800)(-750 1800);
WIRE 16 -1 (-950 1800)(-950 1850);
WIRE 16 -1 (-950 1850)(-750 1850);
WIRE 16 -1 (-950 1850)(-950 1900);
WIRE 16 -1 (-950 1900)(-750 1900);
WIRE 16 -1 (-950 1900)(-950 1950);
WIRE 16 -1 (-950 1950)(-750 1950);
WIRE 16 -1 (-950 1950)(-950 2000);
WIRE 16 -1 (-950 2000)(-950 2050);
WIRE 16 -1 (-950 2000)(-750 2000);
WIRE 16 -1 (-950 2050)(-750 2050);
WIRE 16 -1 (-950 2050)(-950 2100);
WIRE 16 -1 (-950 2100)(-750 2100);
WIRE 16 -1 (-950 2100)(-950 2150);
WIRE 16 -1 (-950 2150)(-750 2150);
WIRE 16 -1 (-950 2150)(-950 2200);
WIRE 16 -1 (-950 2200)(-750 2200);
WIRE 16 -1 (-950 2200)(-950 2250);
WIRE 16 -1 (-950 2250)(-750 2250);
WIRE 16 -1 (-950 2250)(-950 2300);
WIRE 16 -1 (-950 2300)(-750 2300);
WIRE 16 -1 (-950 2300)(-950 2350);
WIRE 16 -1 (-950 2350)(-750 2350);
WIRE 16 -1 (-950 2350)(-950 2400);
WIRE 16 -1 (-950 2400)(-750 2400);
WIRE 16 -1 (-950 2400)(-950 2450);
WIRE 16 -1 (-950 2450)(-750 2450);
WIRE 16 -1 (-1350 2450)(-950 2450);
WIRE 16 -1 (-1350 2575)(-1350 2450);
WIRE 16 -1 (-950 2550)(-950 2600);
WIRE 16 -1 (-950 2550)(-750 2550);
WIRE 16 -1 (-950 2600)(-750 2600);
WIRE 16 -1 (-1100 2600)(-950 2600);
WIRE 16 -1 (-1100 2700)(-1100 2600);
WIRE 16 -1 (2500 3500)(2500 3550);
WIRE 16 -1 (2500 3450)(2500 3500);
WIRE 16 -1 (2500 3500)(2300 3500);
WIRE 16 -1 (2500 3550)(2300 3550);
WIRE 16 -1 (2500 3400)(2500 3450);
WIRE 16 -1 (2500 3450)(2300 3450);
WIRE 16 -1 (2500 3350)(2500 3400);
WIRE 16 -1 (2500 3400)(2300 3400);
WIRE 16 -1 (2500 3300)(2500 3350);
WIRE 16 -1 (2500 3350)(2300 3350);
WIRE 16 -1 (2500 3250)(2500 3300);
WIRE 16 -1 (2500 3300)(2300 3300);
WIRE 16 -1 (2500 3200)(2500 3250);
WIRE 16 -1 (2500 3250)(2300 3250);
WIRE 16 -1 (2500 3150)(2500 3200);
WIRE 16 -1 (2500 3200)(2300 3200);
WIRE 16 -1 (2500 3100)(2500 3150);
WIRE 16 -1 (2500 3150)(2300 3150);
WIRE 16 -1 (2500 3100)(2300 3100);
WIRE 16 -1 (2500 3050)(2500 3100);
WIRE 16 -1 (2500 3000)(2500 3050);
WIRE 16 -1 (2500 3050)(2300 3050);
WIRE 16 -1 (2500 2950)(2500 3000);
WIRE 16 -1 (2500 3000)(2300 3000);
WIRE 16 -1 (2500 2900)(2500 2950);
WIRE 16 -1 (2500 2950)(2300 2950);
WIRE 16 -1 (2500 2850)(2500 2900);
WIRE 16 -1 (2500 2900)(2300 2900);
WIRE 16 -1 (2500 2800)(2500 2850);
WIRE 16 -1 (2500 2850)(2300 2850);
WIRE 16 -1 (2500 2750)(2500 2800);
WIRE 16 -1 (2500 2800)(2300 2800);
WIRE 16 -1 (2500 2700)(2500 2750);
WIRE 16 -1 (2500 2750)(2300 2750);
WIRE 16 -1 (2500 2650)(2500 2700);
WIRE 16 -1 (2500 2700)(2300 2700);
WIRE 16 -1 (2500 2600)(2500 2650);
WIRE 16 -1 (2500 2650)(2300 2650);
WIRE 16 -1 (2500 2600)(2300 2600);
WIRE 16 -1 (2500 2550)(2500 2600);
WIRE 16 -1 (2500 2500)(2500 2550);
WIRE 16 -1 (2500 2550)(2300 2550);
WIRE 16 -1 (2500 2450)(2500 2500);
WIRE 16 -1 (2500 2500)(2300 2500);
WIRE 16 -1 (2500 2400)(2500 2450);
WIRE 16 -1 (2500 2450)(2300 2450);
WIRE 16 -1 (2500 2350)(2500 2400);
WIRE 16 -1 (2500 2400)(2300 2400);
WIRE 16 -1 (2500 2300)(2500 2350);
WIRE 16 -1 (2500 2350)(2300 2350);
WIRE 16 -1 (2500 2250)(2500 2300);
WIRE 16 -1 (2500 2300)(2300 2300);
WIRE 16 -1 (2500 2200)(2500 2250);
WIRE 16 -1 (2500 2250)(2300 2250);
WIRE 16 -1 (2500 2150)(2500 2200);
WIRE 16 -1 (2500 2200)(2300 2200);
WIRE 16 -1 (2500 2100)(2500 2150);
WIRE 16 -1 (2500 2150)(2300 2150);
WIRE 16 -1 (2500 2050)(2500 2100);
WIRE 16 -1 (2500 2100)(2300 2100);
WIRE 16 -1 (2500 2050)(2300 2050);
WIRE 16 -1 (2500 2000)(2500 2050);
WIRE 16 -1 (2500 1950)(2500 2000);
WIRE 16 -1 (2500 2000)(2300 2000);
WIRE 16 -1 (2500 1900)(2500 1950);
WIRE 16 -1 (2500 1950)(2300 1950);
WIRE 16 -1 (2500 1850)(2500 1900);
WIRE 16 -1 (2500 1900)(2300 1900);
WIRE 16 -1 (2500 1800)(2500 1850);
WIRE 16 -1 (2500 1850)(2300 1850);
WIRE 16 -1 (2500 1750)(2500 1800);
WIRE 16 -1 (2500 1800)(2300 1800);
WIRE 16 -1 (2500 1700)(2500 1750);
WIRE 16 -1 (2500 1750)(2300 1750);
WIRE 16 -1 (2500 1650)(2500 1700);
WIRE 16 -1 (2500 1700)(2300 1700);
WIRE 16 -1 (2500 1600)(2500 1650);
WIRE 16 -1 (2500 1650)(2300 1650);
WIRE 16 -1 (2500 1550)(2500 1600);
WIRE 16 -1 (2500 1600)(2300 1600);
WIRE 16 -1 (2500 1550)(2300 1550);
WIRE 16 -1 (2500 1500)(2500 1550);
WIRE 16 -1 (2500 1450)(2500 1500);
WIRE 16 -1 (2500 1500)(2300 1500);
WIRE 16 -1 (2500 1400)(2500 1450);
WIRE 16 -1 (2500 1450)(2300 1450);
WIRE 16 -1 (2500 1350)(2500 1400);
WIRE 16 -1 (2500 1400)(2300 1400);
WIRE 16 -1 (2500 1300)(2500 1350);
WIRE 16 -1 (2500 1350)(2300 1350);
WIRE 16 -1 (2500 1250)(2500 1300);
WIRE 16 -1 (2500 1300)(2300 1300);
WIRE 16 -1 (2500 1150)(2500 1250);
WIRE 16 -1 (2500 1250)(2300 1250);
WIRE 16 -1 (-3175 2050)(-3000 2050);
WIRE 16 -1 (-3175 1950)(-3175 2050);
WIRE 16 -1 (-3000 1950)(-3175 1950);
WIRE 16 -1 (-3175 1950)(-5150 1950);
WIRE 16 -1 (-5150 1950)(-5150 1900);
WIRE 16 -1 (-4650 1450)(-4650 1350);
WIRE 16 -1 (-950 2700)(-750 2700);
WIRE 16 -1 (-950 2750)(-950 2700);
WIRE 16 -1 (-950 2750)(-750 2750);
WIRE 16 -1 (-950 2800)(-950 2750);
WIRE 16 -1 (-950 2800)(-750 2800);
WIRE 16 -1 (-950 2800)(-950 2850);
WIRE 16 -1 (-950 2850)(-750 2850);
WIRE 16 -1 (-950 2900)(-950 2850);
WIRE 16 -1 (-950 2900)(-750 2900);
WIRE 16 -1 (-950 3025)(-950 2900);
WIRE 16 -1 (-3000 2000)(-3275 2000);
WIRE 16 -1 (-3275 2000)(-3275 2100);
WIRE 16 -1 (-3275 2100)(-3000 2100);
WIRE 16 -1 (-5150 2100)(-3275 2100);
WIRE 16 -1 (-5150 2100)(-5150 2200);
WIRE 16 -1 (250 2850)(375 2850);
WIRE 16 -1 (375 2850)(375 2900);
WIRE 16 -1 (250 2900)(375 2900);
WIRE 16 -1 (375 2900)(375 2975);
WIRE 16 -1 (1100 3550)(1300 3550);
WIRE 16 -1 (1100 3500)(1100 3550);
WIRE 16 -1 (1100 3500)(1300 3500);
WIRE 16 -1 (1100 3450)(1100 3500);
WIRE 16 -1 (1100 3450)(1300 3450);
WIRE 16 -1 (1100 3400)(1100 3450);
WIRE 16 -1 (1100 3400)(1300 3400);
WIRE 16 -1 (1100 3350)(1100 3400);
WIRE 16 -1 (1100 3350)(1300 3350);
WIRE 16 -1 (1100 3300)(1100 3350);
WIRE 16 -1 (1100 3300)(1300 3300);
WIRE 16 -1 (1100 3250)(1100 3300);
WIRE 16 -1 (1100 3250)(1300 3250);
WIRE 16 -1 (1100 3200)(1100 3250);
WIRE 16 -1 (1100 3200)(1300 3200);
WIRE 16 -1 (1100 3150)(1100 3200);
WIRE 16 -1 (1100 3150)(1300 3150);
WIRE 16 -1 (1100 3100)(1100 3150);
WIRE 16 -1 (1100 3100)(1300 3100);
WIRE 16 -1 (1100 3050)(1100 3100);
WIRE 16 -1 (1100 3050)(1300 3050);
WIRE 16 -1 (1100 3000)(1100 3050);
WIRE 16 -1 (1100 3000)(1300 3000);
WIRE 16 -1 (1100 2950)(1100 3000);
WIRE 16 -1 (1100 2950)(1300 2950);
WIRE 16 -1 (1100 2900)(1100 2950);
WIRE 16 -1 (1100 2900)(1300 2900);
WIRE 16 -1 (1100 2850)(1100 2900);
WIRE 16 -1 (1100 2850)(1300 2850);
WIRE 16 -1 (1100 2800)(1100 2850);
WIRE 16 -1 (1100 2800)(1300 2800);
WIRE 16 -1 (1100 2750)(1100 2800);
WIRE 16 -1 (1100 2750)(1300 2750);
WIRE 16 -1 (1100 2700)(1100 2750);
WIRE 16 -1 (1100 2700)(1300 2700);
WIRE 16 -1 (1100 2650)(1100 2700);
WIRE 16 -1 (1100 2650)(1300 2650);
WIRE 16 -1 (1100 2600)(1100 2650);
WIRE 16 -1 (1100 2600)(1300 2600);
WIRE 16 -1 (1100 2550)(1100 2600);
WIRE 16 -1 (1100 2550)(1300 2550);
WIRE 16 -1 (1100 2500)(1100 2550);
WIRE 16 -1 (1100 2500)(1300 2500);
WIRE 16 -1 (1100 2450)(1100 2500);
WIRE 16 -1 (1100 2450)(1300 2450);
WIRE 16 -1 (1100 2400)(1100 2450);
WIRE 16 -1 (1100 2400)(1300 2400);
WIRE 16 -1 (1100 2350)(1100 2400);
WIRE 16 -1 (1100 2350)(1300 2350);
WIRE 16 -1 (1100 2300)(1100 2350);
WIRE 16 -1 (1100 2300)(1300 2300);
WIRE 16 -1 (1100 2250)(1100 2300);
WIRE 16 -1 (1100 2250)(1300 2250);
WIRE 16 -1 (1100 2200)(1100 2250);
WIRE 16 -1 (1100 2200)(1300 2200);
WIRE 16 -1 (1100 2150)(1100 2200);
WIRE 16 -1 (1100 2150)(1300 2150);
WIRE 16 -1 (1100 2100)(1100 2150);
WIRE 16 -1 (1100 2100)(1300 2100);
WIRE 16 -1 (1100 2050)(1100 2100);
WIRE 16 -1 (1100 2050)(1300 2050);
WIRE 16 -1 (1100 2000)(1100 2050);
WIRE 16 -1 (1100 2000)(1300 2000);
WIRE 16 -1 (1100 1950)(1100 2000);
WIRE 16 -1 (1100 1950)(1300 1950);
WIRE 16 -1 (1100 1900)(1100 1950);
WIRE 16 -1 (1100 1900)(1300 1900);
WIRE 16 -1 (1100 1850)(1100 1900);
WIRE 16 -1 (1100 1850)(1300 1850);
WIRE 16 -1 (1100 1800)(1100 1850);
WIRE 16 -1 (1100 1800)(1300 1800);
WIRE 16 -1 (1100 1750)(1100 1800);
WIRE 16 -1 (1100 1750)(1300 1750);
WIRE 16 -1 (1100 1700)(1100 1750);
WIRE 16 -1 (1100 1700)(1300 1700);
WIRE 16 -1 (1100 1650)(1100 1700);
WIRE 16 -1 (1100 1650)(1300 1650);
WIRE 16 -1 (1100 1600)(1100 1650);
WIRE 16 -1 (1100 1600)(1300 1600);
WIRE 16 -1 (1100 1550)(1100 1600);
WIRE 16 -1 (1100 1550)(1300 1550);
WIRE 16 -1 (1100 1500)(1100 1550);
WIRE 16 -1 (1100 1500)(1300 1500);
WIRE 16 -1 (1100 1450)(1100 1500);
WIRE 16 -1 (1100 1450)(1300 1450);
WIRE 16 -1 (1100 1400)(1100 1450);
WIRE 16 -1 (1100 1400)(1300 1400);
WIRE 16 -1 (1100 1350)(1100 1400);
WIRE 16 -1 (1100 1350)(1300 1350);
WIRE 16 -1 (1100 1300)(1100 1350);
WIRE 16 -1 (1100 1300)(1300 1300);
WIRE 16 -1 (1100 1250)(1100 1300);
WIRE 16 -1 (1100 1250)(1300 1250);
WIRE 16 -1 (1100 1150)(1100 1250);
WIRE 16 -1 (-3000 2200)(-4000 2200);
FORCEPROP 2 LAST SIG_NAME M_L_ACT_N
J 0
(-3950 2210);
DISPLAY 0.617021 (-3950 2210);
PAINT ORANGE (-3950 2210);
WIRE 16 -1 (-3000 1750)(-4650 1750);
FORCEPROP 2 LAST SIG_NAME M_L_VREF
J 0
(-3750 1760);
DISPLAY 0.617021 (-3750 1760);
PAINT ORANGE (-3750 1760);
WIRE 16 -1 (-4650 1750)(-4650 1650);
WIRE 16 -1 (-4750 1750)(-4650 1750);
WIRE 16 -1 (-3850 1650)(-3000 1650);
FORCEPROP 2 LAST SIG_NAME TP_CH_L_DIMM_L0_RFU_2
J 0
(-3800 1660);
DISPLAY 0.617021 (-3800 1660);
PAINT ORANGE (-3800 1660);
FORCEPROP 2 LASTPROP $XRERR UNIQUE?
J 0
(-4090 1650);
DISPLAY 0.638298 (-4090 1650);
PAINT MONO (-4090 1650);
DISPLAY INVISIBLE (-4090 1650);
WIRE 16 -1 (-3850 1550)(-3000 1550);
FORCEPROP 2 LAST SIG_NAME TP_CH_L_DIMM_L0_RFU_0
J 0
(-3800 1560);
DISPLAY 0.617021 (-3800 1560);
PAINT ORANGE (-3800 1560);
FORCEPROP 2 LASTPROP $XRERR UNIQUE?
J 0
(-4090 1550);
DISPLAY 0.638298 (-4090 1550);
PAINT MONO (-4090 1550);
DISPLAY INVISIBLE (-4090 1550);
WIRE 16 -1 (-3850 1600)(-3000 1600);
FORCEPROP 2 LAST SIG_NAME TP_CH_L_DIMM_L0_RFU_1
J 0
(-3800 1610);
DISPLAY 0.617021 (-3800 1610);
PAINT ORANGE (-3800 1610);
FORCEPROP 2 LASTPROP $XRERR UNIQUE?
J 0
(-4090 1600);
DISPLAY 0.638298 (-4090 1600);
PAINT MONO (-4090 1600);
DISPLAY INVISIBLE (-4090 1600);
WIRE 16 -1 (-3000 1900)(-3800 1900);
WIRE 16 -1 (-3800 1850)(-3000 1850);
FORCEPROP 2 LAST SIG_NAME SMB_DDR_KLM_VPP_SCL
J 0
(-3760 1860);
DISPLAY 0.617021 (-3760 1860);
PAINT ORANGE (-3760 1860);
WIRE 16 -1 (-3850 1450)(-3000 1450);
FORCEPROP 2 LAST SIG_NAME FM_ADR_COMPLETE_KLM_N
J 0
(-3800 1460);
DISPLAY 0.617021 (-3800 1460);
PAINT ORANGE (-3800 1460);
WIRE 16 -1 (-3450 2300)(-3000 2300);
WIRE 16 -1 (-3450 2300)(-3450 2550);
WIRE 16 -1 (-3450 2550)(-4175 2550);
FORCEPROP 2 LAST SIG_NAME FM_DIMM_EVENT_COD_N
J 0
(-4159 2572);
DISPLAY 0.617021 (-4159 2572);
PAINT ORANGE (-4159 2572);
WIRE 16 -1 (-3000 2400)(-3350 2400);
WIRE 16 -1 (-3350 2400)(-3350 2850);
WIRE 16 -1 (-3350 2850)(-3800 2850);
FORCEPROP 2 LAST SIG_NAME M_L_PAR
J 0
(-3775 2860);
DISPLAY 0.617021 (-3775 2860);
PAINT ORANGE (-3775 2860);
WIRE 16 -1 (-3000 2350)(-3400 2350);
WIRE 16 -1 (-3400 2350)(-3400 2800);
WIRE 16 -1 (-3400 2800)(-3800 2800);
FORCEPROP 2 LAST SIG_NAME M_KLM_RST_N
J 0
(-3775 2810);
DISPLAY 0.617021 (-3775 2810);
PAINT ORANGE (-3775 2810);
WIRE 16 -1 (-3175 3450)(-3000 3450);
WIRE 16 -1 (-3175 3500)(-3175 3450);
WIRE 16 -1 (-3175 3500)(-3800 3500);
FORCEPROP 2 LAST SIG_NAME M_L_C<2>
J 0
(-3775 3510);
DISPLAY 0.617021 (-3775 3510);
PAINT ORANGE (-3775 3510);
WIRE 16 -1 (-3000 3800)(-3200 3800);
WIRE 16 -1 (-3000 3850)(-3200 3850);
WIRE 16 -1 (-3000 3900)(-3200 3900);
WIRE 16 -1 (-3000 3950)(-3200 3950);
WIRE 16 -1 (-3000 3700)(-3200 3700);
WIRE 16 -1 (-3000 3650)(-3400 3650);
WIRE 16 -1 (-3000 3400)(-3200 3400);
WIRE 16 -1 (-3000 3600)(-3200 3600);
WIRE 16 -1 (-3000 3350)(-3200 3350);
WIRE 16 -1 (-3000 3300)(-3200 3300);
WIRE 16 -1 (-3000 4050)(-3200 4050);
WIRE 16 -1 (-3000 2800)(-3200 2800);
WIRE 16 -1 (-3000 2750)(-3200 2750);
WIRE 16 -1 (-3000 2700)(-3200 2700);
WIRE 16 -1 (-3000 2650)(-3200 2650);
WIRE 16 -1 (-3000 2600)(-3200 2600);
WIRE 16 -1 (-3000 2550)(-3200 2550);
WIRE 16 -1 (-3000 2500)(-3200 2500);
WIRE 16 -1 (-3000 3550)(-3400 3550);
WIRE 16 -1 (-3000 3150)(-3200 3150);
WIRE 16 -1 (-3000 2850)(-3200 2850);
WIRE 16 -1 (-3000 2950)(-3200 2950);
WIRE 16 -1 (-3000 3000)(-3200 3000);
WIRE 16 -1 (-3000 3100)(-3200 3100);
WIRE 16 -1 (-3000 3250)(-3200 3250);
WIRE 16 -1 (-3000 2250)(-4025 2250);
FORCEPROP 2 LAST SIG_NAME M_L_ALERT_N
J 0
(-3975 2260);
DISPLAY 0.617021 (-3975 2260);
PAINT ORANGE (-3975 2260);
WIRE 16 -1 (-1800 1750)(-2000 1750);
WIRE 16 -1 (-1800 1800)(-2000 1800);
WIRE 16 -1 (-1800 1850)(-2000 1850);
WIRE 16 -1 (-1800 1900)(-2000 1900);
WIRE 16 -1 (-1800 1950)(-2000 1950);
WIRE 16 -1 (-1800 2000)(-2000 2000);
WIRE 16 -1 (-1800 2300)(-2000 2300);
WIRE 16 -1 (-1800 2250)(-2000 2250);
WIRE 16 -1 (-1800 2200)(-2000 2200);
WIRE 16 -1 (-1800 2150)(-2000 2150);
WIRE 16 -1 (-1800 2100)(-2000 2100);
WIRE 16 -1 (-1800 2050)(-2000 2050);
WIRE 16 -1 (-1800 2550)(-2000 2550);
WIRE 16 -1 (-1800 2450)(-2000 2450);
WIRE 16 -1 (-1800 2400)(-2000 2400);
WIRE 16 -1 (-1800 2350)(-2000 2350);
WIRE 16 -1 (-1800 2500)(-2000 2500);
WIRE 16 -1 (-1800 2700)(-2000 2700);
WIRE 16 -1 (-1800 2800)(-2000 2800);
WIRE 16 -1 (-1800 2750)(-2000 2750);
WIRE 16 -1 (-1800 2650)(-2000 2650);
WIRE 16 -1 (-1800 2600)(-2000 2600);
WIRE 16 -1 (-1800 2850)(-2000 2850);
WIRE 16 -1 (-1800 2900)(-2000 2900);
WIRE 16 -1 (-1800 2950)(-2000 2950);
WIRE 16 -1 (-1800 3000)(-2000 3000);
WIRE 16 -1 (-1800 3050)(-2000 3050);
WIRE 16 -1 (-1800 3200)(-2000 3200);
WIRE 16 -1 (-1800 3150)(-2000 3150);
WIRE 16 -1 (-1800 3300)(-2000 3300);
WIRE 16 -1 (-1800 3250)(-2000 3250);
WIRE 16 -1 (-1800 3100)(-2000 3100);
WIRE 16 -1 (-1800 3400)(-2000 3400);
WIRE 16 -1 (-1800 3450)(-2000 3450);
WIRE 16 -1 (-1800 3350)(-2000 3350);
WIRE 16 -1 (-1800 3500)(-2000 3500);
WIRE 16 -1 (-1800 3550)(-2000 3550);
WIRE 16 -1 (-1800 3600)(-2000 3600);
WIRE 16 -1 (-1800 3700)(-2000 3700);
WIRE 16 -1 (-1800 3800)(-2000 3800);
WIRE 16 -1 (-1800 3750)(-2000 3750);
WIRE 16 -1 (-1800 3650)(-2000 3650);
WIRE 16 -1 (-1800 3900)(-2000 3900);
WIRE 16 -1 (-1800 3950)(-2000 3950);
WIRE 16 -1 (-1800 4000)(-2000 4000);
WIRE 16 -1 (-1800 4050)(-2000 4050);
WIRE 16 -1 (-1800 3850)(-2000 3850);
WIRE 16 -1 (-3000 4100)(-3200 4100);
WIRE 16 -1 (-3000 4650)(-3200 4650);
WIRE 16 -1 (-3000 4700)(-3200 4700);
WIRE 16 -1 (-3000 4900)(-3200 4900);
WIRE 16 -1 (-3000 4200)(-3200 4200);
WIRE 16 -1 (-3000 4250)(-3200 4250);
WIRE 16 -1 (-3000 4300)(-3200 4300);
WIRE 16 -1 (-3000 4350)(-3200 4350);
WIRE 16 -1 (-3000 4400)(-3200 4400);
WIRE 16 -1 (-3000 4450)(-3200 4450);
WIRE 16 -1 (-3000 4500)(-3200 4500);
WIRE 16 -1 (-3000 4150)(-3200 4150);
WIRE 16 -1 (-3000 4550)(-3200 4550);
WIRE 16 -1 (-3000 4600)(-3200 4600);
WIRE 16 -1 (-3000 4750)(-3200 4750);
WIRE 16 -1 (-3000 4800)(-3200 4800);
WIRE 16 -1 (-3000 4850)(-3200 4850);
WIRE 16 -1 (-1800 4100)(-2000 4100);
WIRE 16 -1 (-1800 4150)(-2000 4150);
WIRE 16 -1 (-1800 4200)(-2000 4200);
WIRE 16 -1 (-1800 4250)(-2000 4250);
WIRE 16 -1 (-1800 4300)(-2000 4300);
WIRE 16 -1 (-1800 4350)(-2000 4350);
WIRE 16 -1 (-1800 4500)(-2000 4500);
WIRE 16 -1 (-1800 4550)(-2000 4550);
WIRE 16 -1 (-1800 4600)(-2000 4600);
WIRE 16 -1 (-1800 4450)(-2000 4450);
WIRE 16 -1 (-1800 4400)(-2000 4400);
WIRE 16 -1 (-1800 4800)(-2000 4800);
WIRE 16 -1 (-1800 4650)(-2000 4650);
WIRE 16 -1 (-1800 4750)(-2000 4750);
WIRE 16 -1 (-1800 4700)(-2000 4700);
WIRE 16 -1 (-1800 4850)(-2000 4850);
WIRE 16 -1 (-1800 4900)(-2000 4900);
WIRE 16 -1 (850 3400)(450 3400);
WIRE 16 -1 (650 3450)(450 3450);
WIRE 16 -1 (850 3500)(450 3500);
WIRE 16 -1 (650 3550)(450 3550);
WIRE 16 -1 (850 3600)(450 3600);
WIRE 16 -1 (650 3650)(450 3650);
WIRE 16 -1 (850 3700)(450 3700);
WIRE 16 -1 (650 3750)(450 3750);
WIRE 16 -1 (850 3800)(450 3800);
WIRE 16 -1 (650 3850)(450 3850);
WIRE 16 -1 (850 3900)(450 3900);
WIRE 16 -1 (650 3950)(450 3950);
WIRE 16 -1 (850 4000)(450 4000);
WIRE 16 -1 (650 4050)(450 4050);
WIRE 16 -1 (850 4400)(450 4400);
WIRE 16 -1 (650 4450)(450 4450);
WIRE 16 -1 (850 4500)(450 4500);
WIRE 16 -1 (650 4550)(450 4550);
WIRE 16 -1 (850 4600)(450 4600);
WIRE 16 -1 (650 4650)(450 4650);
WIRE 16 -1 (850 4700)(450 4700);
WIRE 16 -1 (650 4750)(450 4750);
WIRE 16 -1 (850 4800)(450 4800);
WIRE 16 -1 (650 4850)(450 4850);
WIRE 16 -1 (850 4900)(450 4900);
WIRE 16 -1 (650 4950)(450 4950);
WIRE 16 -1 (850 5000)(450 5000);
WIRE 16 -1 (650 5050)(450 5050);
WIRE 16 -1 (850 5100)(450 5100);
WIRE 16 -1 (850 4100)(450 4100);
WIRE 16 -1 (650 4150)(450 4150);
WIRE 16 -1 (850 4200)(450 4200);
WIRE 16 -1 (650 4250)(450 4250);
WIRE 16 -1 (850 4300)(450 4300);
WIRE 16 -1 (650 4350)(450 4350);
WIRE 16 -1 (650 5150)(450 5150);
DOT 1 (-3175 1950);
DOT 1 (-950 1750);
DOT 1 (1100 1800);
DOT 1 (1100 3500);
DOT 1 (1100 2550);
DOT 1 (-950 2800);
DOT 1 (375 2900);
DOT 1 (-950 2750);
DOT 1 (1100 2850);
DOT 1 (1100 1750);
DOT 1 (-950 1900);
DOT 1 (-950 2350);
DOT 1 (-950 1300);
DOT 1 (-950 1350);
DOT 1 (-950 1400);
DOT 1 (-950 1450);
DOT 1 (-950 1500);
DOT 1 (-950 1550);
DOT 1 (-950 1600);
DOT 1 (-950 1650);
DOT 1 (-950 1700);
DOT 1 (-950 2000);
DOT 1 (-950 2050);
DOT 1 (-950 2400);
DOT 1 (-950 2450);
DOT 1 (-950 2600);
DOT 1 (-950 2850);
DOT 1 (-950 2900);
DOT 1 (1100 3400);
DOT 1 (1100 1250);
DOT 1 (1100 1300);
DOT 1 (1100 1350);
DOT 1 (1100 1400);
DOT 1 (1100 1450);
DOT 1 (1100 1500);
DOT 1 (1100 1600);
DOT 1 (1100 1550);
DOT 1 (1100 1650);
DOT 1 (1100 1700);
DOT 1 (1100 1850);
DOT 1 (1100 1900);
DOT 1 (1100 1950);
DOT 1 (1100 2000);
DOT 1 (1100 2050);
DOT 1 (1100 2100);
DOT 1 (1100 2150);
DOT 1 (1100 2200);
DOT 1 (1100 2250);
DOT 1 (1100 2300);
DOT 1 (1100 2350);
DOT 1 (1100 2400);
DOT 1 (1100 2450);
DOT 1 (1100 2500);
DOT 1 (1100 2600);
DOT 1 (1100 2650);
DOT 1 (1100 2700);
DOT 1 (1100 2750);
DOT 1 (1100 2800);
DOT 1 (1100 2900);
DOT 1 (1100 2950);
DOT 1 (1100 3000);
DOT 1 (1100 3050);
DOT 1 (1100 3100);
DOT 1 (1100 3150);
DOT 1 (1100 3200);
DOT 1 (1100 3300);
DOT 1 (1100 3250);
DOT 1 (1100 3350);
DOT 1 (1100 3450);
DOT 1 (2500 1250);
DOT 1 (2500 1300);
DOT 1 (2500 1350);
DOT 1 (2500 1400);
DOT 1 (2500 1450);
DOT 1 (2500 1500);
DOT 1 (2500 1600);
DOT 1 (2500 1550);
DOT 1 (2500 1650);
DOT 1 (2500 1700);
DOT 1 (2500 1750);
DOT 1 (2500 1800);
DOT 1 (2500 1850);
DOT 1 (2500 1900);
DOT 1 (2500 2000);
DOT 1 (2500 1950);
DOT 1 (2500 2050);
DOT 1 (2500 2100);
DOT 1 (2500 2150);
DOT 1 (2500 2200);
DOT 1 (2500 2250);
DOT 1 (2500 2300);
DOT 1 (2500 2400);
DOT 1 (2500 2350);
DOT 1 (2500 2450);
DOT 1 (2500 2500);
DOT 1 (2500 2550);
DOT 1 (2500 2600);
DOT 1 (2500 2650);
DOT 1 (2500 2700);
DOT 1 (2500 2750);
DOT 1 (2500 2800);
DOT 1 (2500 2900);
DOT 1 (2500 2850);
DOT 1 (2500 2950);
DOT 1 (2500 3000);
DOT 1 (2500 3050);
DOT 1 (2500 3100);
DOT 1 (2500 3150);
DOT 1 (2500 3200);
DOT 1 (2500 3300);
DOT 1 (2500 3250);
DOT 1 (2500 3350);
DOT 1 (2500 3400);
DOT 1 (2500 3450);
DOT 1 (2500 3500);
DOT 1 (-4650 1750);
DOT 1 (-3275 2100);
DOT 1 (-950 1850);
DOT 1 (-950 1950);
DOT 1 (-950 1250);
DOT 1 (-950 1800);
DOT 1 (-950 2100);
DOT 1 (-950 2150);
DOT 1 (-950 2200);
DOT 1 (-950 2250);
DOT 1 (-950 2300);
FORCENOTE
SMBUS ADDR: 0XA4
(-2950 1159) 0;
DISPLAY LEFT (-2950 1159);
DISPLAY 1.957447 (-2950 1159);
PAINT PURPLE (-2950 1159);
FORCENOTE
PLACE CAP NEAR DIMM CONNECTOR
(-5288 1202) 0;
DISPLAY LEFT (-5288 1202);
DISPLAY 1.595745 (-5288 1202);
PAINT PURPLE (-5288 1202);
QUIT
